G04 ================== begin FILE IDENTIFICATION RECORD ==================*
G04 Layout Name:  x887571-005_osp.brd*
G04 Film Name:    lyr6*
G04 File Format:  Gerber RS274X*
G04 File Origin:  Cadence Allegro 16.3-S036*
G04 Origin Date:  Thu Jul 03 00:06:58 2014*
G04 *
G04 Layer:  VIA CLASS/LYR6*
G04 Layer:  PIN/LYR6*
G04 Layer:  ETCH/LYR6*
G04 Layer:  DRAWING FORMAT/COMMON TEXT*
G04 Layer:  BOARD GEOMETRY/LAYER 6 TEXT*
G04 *
G04 Offset:    (0.0000 0.0000)*
G04 Mirror:    No*
G04 Mode:      Positive*
G04 Rotation:  0*
G04 FullContactRelief:  No*
G04 UndefLineWidth:     4.0000*
G04 ================== end FILE IDENTIFICATION RECORD ====================*
%FSLAX25Y25*MOIN*%
%IR0*IPPOS*OFA0.00000B0.00000*MIA0B0*SFA1.00000B1.00000*%
%ADD11C,.022*%
%ADD12C,.05*%
%ADD10C,.032*%
%ADD14C,.027*%
%ADD13C,.054*%
%ADD15C,.079*%
%ADD16C,.01*%
%ADD17C,.02*%
%ADD18C,.012*%
%ADD19C,.013*%
%ADD20C,.015*%
%ADD21C,.004*%
%ADD22C,.005*%
%ADD23C,.006*%
%ADD24C,.0051*%
%ADD25C,.007*%
%ADD26C,.008*%
%ADD27C,.0044*%
%ADD28C,.032*%
%ADD33C,.08*%
%ADD35C,.063*%
%ADD37C,.064*%
%ADD32C,.073*%
%ADD29C,.091001*%
%ADD38C,.077*%
%ADD34C,.098*%
%ADD36C,.099*%
%ADD30C,.154001*%
%ADD31C,.186001*%
G75*
%LPD*%
G75*
G36*
G01X-1626000Y-137500D02*
X-1630000Y-133500D01*
Y-73000D01*
X-1628000Y-71000D01*
Y-60000D01*
X-1620000Y-52000D01*
X-1513500D01*
X-1503000Y-62500D01*
X-1485200D01*
X-1484600Y-63100D01*
Y-73400D01*
X-1484700Y-73500D01*
X-1492500D01*
X-1495000Y-76000D01*
Y-81072D01*
X-1496728Y-82800D01*
X-1503200D01*
X-1523000Y-63000D01*
X-1586000D01*
X-1613000Y-90000D01*
Y-94136D01*
G02X-1613907Y-94426I-500J0D01*
G03Y-97385I-2077J-1479D01*
G02X-1613000Y-97675I407J-290D01*
G01Y-110671D01*
G02X-1613907Y-110962I-500J0D01*
G03Y-113920I-2077J-1479D01*
G02X-1613000Y-114210I407J-290D01*
G01Y-137500D01*
X-1615481D01*
X-1615504Y-137496D01*
G03X-1616464I-480J-2504D01*
G01X-1616487Y-137500D01*
X-1626000D01*
G37*
G36*
G01X-1454900Y-184700D02*
Y-74100D01*
X-1462000Y-67000D01*
X-1467000D01*
X-1474000Y-60000D01*
X-1502500D01*
X-1512000Y-50500D01*
X-1620000D01*
X-1626000Y-44500D01*
Y-27142D01*
X-1621322Y-22464D01*
X-1621199Y-22481D01*
G03X-1617131Y-18937I490J3544D01*
G01Y16175D01*
X-1616226Y17080D01*
X-1461294D01*
X-1460389Y16175D01*
Y-14409D01*
G03X-1452283Y-22515I8106J0D01*
G01X-1448346D01*
G03X-1440241Y-14409I0J8106D01*
G01Y9213D01*
G02X-1432598Y16855I7643J0D01*
G01X-414000D01*
Y14029D01*
X-414149Y13963D01*
G03Y11037I649J-1463D01*
G01X-414000Y10971D01*
Y-20192D01*
G03X-414141Y-27460I1598J-3667D01*
G01X-414000Y-27528D01*
Y-27900D01*
X-415500Y-29400D01*
X-440388D01*
X-440426Y-29195D01*
G03X-443597Y-29578I-1574J-285D01*
G01X-443590Y-29690D01*
X-454300Y-40400D01*
Y-68993D01*
G03Y-69007I1600J-7D01*
G01Y-69800D01*
X-445390Y-78710D01*
G02X-445433Y-79456I-354J-354D01*
G03X-442934Y-80169I993J-1254D01*
G02X-442464Y-79500I471J169D01*
G01X-431513D01*
X-431495Y-79730D01*
G03X-428305I1595J130D01*
G01X-428287Y-79500D01*
X-414000D01*
Y-91058D01*
G03Y-98391I1598J-3667D01*
G01Y-126491D01*
G03Y-133824I1598J-3667D01*
G01Y-168617D01*
G03Y-175950I1598J-3667D01*
G01Y-178885D01*
X-415060Y-179945D01*
X-572055D01*
X-580500Y-171500D01*
Y-69000D01*
X-590500Y-59000D01*
X-719000D01*
X-749600Y-89600D01*
X-749700D01*
X-750800Y-90700D01*
Y-179700D01*
X-752300Y-181200D01*
X-931000D01*
X-931652Y-180548D01*
Y-48568D01*
X-939720Y-40500D01*
X-951856D01*
G02X-952313Y-39798I0J500D01*
G03X-967765I-7726J3422D01*
G02X-968223Y-40500I-457J-202D01*
G01X-992728D01*
G03X-992770Y-40361I-1552J-390D01*
G01Y-39740D01*
X-993168D01*
G03X-994633Y-39329I-1112J-1150D01*
G02X-995224Y-38704I-110J488D01*
G03X-1011428Y-38844I-8123J2328D01*
G02X-1011906Y-39490I-478J-146D01*
G01X-1014770D01*
Y-40600D01*
X-1032200D01*
X-1043316Y-51716D01*
G02X-1044010Y-51729I-354J354D01*
G03X-1046271Y-53990I-1090J-1171D01*
G02X-1046284Y-54684I-366J-341D01*
G01X-1050300Y-58700D01*
X-1062240D01*
G02X-1062564Y-57819I0J500D01*
G03X-1064636I-1036J1219D01*
G02X-1064960Y-58700I-324J-381D01*
G01X-1145800D01*
Y-61828D01*
G03X-1146028Y-64665I4560J-1794D01*
G01X-1145999Y-64799D01*
X-1166430Y-85230D01*
G02X-1167283Y-84876I-354J354D01*
G01Y-80819D01*
X-1167208Y-80745D01*
G03X-1190669Y-80818I-11768J12005D01*
G01Y-89000D01*
X-1215900D01*
X-1274600Y-147700D01*
X-1282290D01*
Y-168034D01*
G02X-1282536Y-168284I-250J0D01*
G03Y-176283I56J-4000D01*
G02X-1282290Y-176533I-4J-250D01*
G01Y-181530D01*
X-1285460Y-184700D01*
X-1454900D01*
G37*
G36*
G01X-1137450Y-184850D02*
Y-173400D01*
X-1126566D01*
G02X-1126164Y-174198I0J-500D01*
G03X-1123593I1285J-953D01*
G02X-1123191Y-173400I402J298D01*
G01X-1097887D01*
G02X-1097485Y-174198I0J-500D01*
G03X-1094915I1285J-953D01*
G02X-1094513Y-173400I402J298D01*
G01X-1090000D01*
Y-156928D01*
X-1086780Y-153708D01*
Y-139942D01*
X-1090000Y-136722D01*
Y-128000D01*
G03X-1089646Y-126288I-4291J1780D01*
G02X-1088775Y-125961I500J-7D01*
G03X-1089096Y-119789I3637J3283D01*
G02X-1090000Y-119494I-404J295D01*
G01Y-107100D01*
X-1105000Y-92100D01*
Y-87521D01*
G03X-1103137Y-85537I-2500J4214D01*
G01X-1102400Y-84800D01*
X-1089805D01*
G03X-1080471I4667J1493D01*
G01X-1066100D01*
X-1064500Y-86400D01*
Y-143724D01*
X-1064501Y-143736D01*
G03Y-146263I12888J-1263D01*
G01X-1064500Y-146276D01*
Y-184850D01*
X-1137450D01*
G37*
G36*
G01X-893782Y-186850D02*
X-873782D01*
Y-184850D01*
X-893782D01*
X-903782D01*
Y-186850D01*
X-893782D01*
G37*
G36*
G01X-292100Y-46800D02*
X-298800Y-40100D01*
X-318000D01*
X-319419Y-41519D01*
G02X-320232Y-41364I-354J354D01*
G03X-322336Y-43468I-1468J-636D01*
G02X-322181Y-44281I-199J-459D01*
G01X-329400Y-51500D01*
X-335442D01*
X-335481Y-51486D01*
G03X-336519I-519J-1514D01*
G01X-336558Y-51500D01*
X-374500D01*
X-400500Y-77500D01*
X-443100D01*
X-450550Y-70050D01*
Y-40550D01*
X-442000Y-32000D01*
X-409500D01*
X-403500Y-26000D01*
Y10500D01*
X-403400Y10600D01*
X-172200D01*
X-165300Y3700D01*
Y-54600D01*
X-185893D01*
G03X-185907I-7J-1600D01*
G01X-192600D01*
X-193950Y-55950D01*
Y-141319D01*
G03Y-148681I12416J-3681D01*
G01Y-183500D01*
X-212900D01*
Y-174700D01*
X-210600Y-172400D01*
Y-124709D01*
G03Y-120646I-4459J2032D01*
G01Y-98983D01*
X-210800Y-98900D01*
X-212491Y-97209D01*
X-212316Y-97033D01*
G03X-217761Y-91588I-2743J2702D01*
G01X-217938Y-91762D01*
X-262900Y-46800D01*
X-292100D01*
G37*
%LPC*%
G75*
G36*
G01X-549173Y-104441D02*
Y-115984D01*
G02X-572559I-11693J0D01*
G01Y-104441D01*
G02X-549173I11693J12078D01*
G37*
G36*
G01X-1411378Y-134126D02*
Y-145669D01*
G02X-1434764I-11693J0D01*
G01Y-134126D01*
G02X-1411378I11693J12078D01*
G37*
G36*
G01X-1347998Y-116208D02*
G02X-1347689Y-120301I-8891J-2729D01*
G02X-1347998Y-116208I-9199J1364D01*
G37*
G36*
G01X-490095Y-158465D02*
G03X-490143Y-157514I-177J468D01*
G02X-483477I3333J12514D01*
G03X-483525Y-158465I129J-483D01*
G02X-490095I-3285J-8701D01*
G37*
G36*
G01X-1347998Y-169894D02*
G02X-1360173Y-158465I-8891J2729D01*
G03X-1360221Y-157514I-177J468D01*
G02X-1353556I3333J12514D01*
G03X-1353604Y-158465I129J-483D01*
G02X-1347998Y-164437I-3285J-8701D01*
G02Y-169894I-8891J-2729D01*
G37*
G36*
G01X-1450413Y-73798D02*
G02X-1451378Y-72526I-1587J-202D01*
G03X-1450687Y-72002I194J461D01*
G02X-1450693Y-71655I1587J202D01*
G03X-1451336Y-71131I-498J45D01*
G02X-1451114Y-68154I-464J1531D01*
G03X-1450400Y-67702I214J452D01*
G02X-1450399Y-67655I1600J2D01*
G03X-1451090Y-67179I-500J14D01*
G02X-1451090Y-64221I-610J1479D01*
G03X-1450400Y-63768I191J462D01*
G02X-1450366Y-63473I1600J-32D01*
G03X-1450731Y-63203I-245J51D01*
G02X-1450966Y-60292I-769J1403D01*
G03X-1450299Y-59840I167J471D01*
G02X-1449234Y-61408I1599J-60D01*
G03X-1449901Y-61860I-167J-471D01*
G02X-1449934Y-62127I-1599J61D01*
G03X-1449569Y-62397I245J-51D01*
G02X-1449410Y-65279I769J-1403D01*
G03X-1450100Y-65732I-191J-462D01*
G02X-1450101Y-65745I-1600J31D01*
G03X-1449410Y-66221I500J-14D01*
G02X-1449486Y-69146I610J-1479D01*
G03X-1450200Y-69598I-214J-452D01*
G02X-1450207Y-69745I-1600J-2D01*
G03X-1449564Y-70269I498J-45D01*
G02X-1449722Y-73274I464J-1531D01*
G03X-1450413Y-73798I-194J-461D01*
G37*
G36*
G01X-1450500Y-82159D02*
G02X-1451338Y-80793I-1599J-41D01*
G03X-1450600Y-80341I238J440D01*
G02X-1450592Y-80142I1599J41D01*
G03X-1451306Y-79642I-498J49D01*
G02X-1450408Y-78358I-694J1442D01*
G03X-1449694Y-78858I498J-49D01*
G02X-1449762Y-81707I694J-1442D01*
G03X-1450500Y-82159I-238J-440D01*
G37*
G36*
G01X-445448Y-144838D02*
G02X-447341Y-147362I3519J-4611D01*
G03X-448048Y-146743I-467J180D01*
G02X-446240Y-144333I-1756J3200D01*
G03X-445448Y-144838I488J-108D01*
G37*
G36*
G01X-1315527D02*
G02X-1317420Y-147362I3519J-4611D01*
G03X-1318127Y-146743I-467J180D01*
G02X-1316318Y-144333I-1756J3200D01*
G03X-1315527Y-144838I488J-108D01*
G37*
G54D28*
X-1618400Y-71600D03*
X-1618300Y-63100D03*
X-1621600Y-61100D03*
Y-65100D03*
X-1618500Y-67200D03*
X-1621600Y-69400D03*
X-1535063Y-22160D03*
X-1530063Y-12160D03*
Y-17160D03*
Y-22160D03*
X-1535063Y-12160D03*
Y-17160D03*
X-1515063Y-12160D03*
Y-17160D03*
Y-22160D03*
X-1525063Y-12160D03*
Y-17160D03*
X-1520063Y-12160D03*
Y-17160D03*
X-1525063Y-22160D03*
X-1520063D03*
X-1500063Y-12160D03*
Y-17160D03*
Y-22160D03*
X-1510063Y-12160D03*
Y-17160D03*
X-1505063Y-12160D03*
Y-17160D03*
X-1510063Y-22160D03*
X-1505063D03*
X-1485063Y-12160D03*
Y-17160D03*
Y-22160D03*
X-1495063Y-12160D03*
Y-17160D03*
X-1490063Y-12160D03*
Y-17160D03*
X-1495063Y-22160D03*
X-1490063D03*
X-1475063D03*
X-1470063Y-12160D03*
Y-17160D03*
Y-22160D03*
X-1480063Y-12160D03*
Y-17160D03*
X-1475063Y-12160D03*
Y-17160D03*
X-1480063Y-22160D03*
X-1450000Y-112500D03*
X-1465063Y-12160D03*
Y-17160D03*
Y-22160D03*
X-1437500Y-175000D03*
X-1450000Y-162500D03*
Y-137500D03*
X-1437500Y-100000D03*
X-1436500Y-87500D03*
X-1450000D03*
X-1448900Y-76100D03*
X-1435000Y1000D03*
X-1425000Y-162500D03*
X-1430500Y-93500D03*
X-1430000Y-75400D03*
X-1421250Y-81250D03*
X-1431500Y-81000D03*
X-1419500Y-18000D03*
X-1420000Y14500D03*
X-1412500Y-175000D03*
X-1406250Y-106250D03*
X-1412000Y-100500D03*
X-1418500Y-93500D03*
X-1406250Y-82500D03*
X-1412500Y-62500D03*
X-1387500Y-175000D03*
Y-150000D03*
X-1400000Y-162500D03*
X-1387300Y-133200D03*
X-1387500Y-125000D03*
X-1400100Y-131550D03*
X-1395000Y-106250D03*
X-1400000Y-112500D03*
X-1400500Y-96500D03*
X-1393750Y-82500D03*
X-1400000Y-75000D03*
X-1387500Y-62500D03*
X-1394500Y-18000D03*
X-1395000Y-500D03*
X-1395518Y14053D03*
X-1371250Y-112500D03*
X-1380000Y-106250D03*
X-1381250Y-82500D03*
X-1375000Y-75000D03*
X-1373800Y-52900D03*
X-1382500Y-8000D03*
Y7000D03*
X-1363750Y-106250D03*
X-1356250Y-82500D03*
X-1368750D03*
X-1362500Y-62500D03*
X-1356700Y-25600D03*
X-1357500Y-8000D03*
X-1370000Y-500D03*
X-1357500Y7000D03*
X-1370000Y14500D03*
X-1350600Y-75000D03*
X-1343200Y-82700D03*
X-1345000Y-500D03*
Y14500D03*
X-1330400Y-74900D03*
X-1324840Y-82120D03*
X-1337500Y-62500D03*
X-1324500Y-26959D03*
X-1332500Y-27500D03*
Y7000D03*
X-1321000Y-94850D03*
X-1313040Y-80810D03*
X-1317700Y-72700D03*
X-1310559Y-74200D03*
X-1317700Y-60200D03*
X-1310559Y-68700D03*
Y-63200D03*
Y-57700D03*
X-1310600Y-46690D03*
X-1310559Y-41200D03*
Y-52200D03*
X-1311200Y-30200D03*
X-1310559Y-35700D03*
X-1320000Y-500D03*
X-1318500Y-6000D03*
X-1320000Y14500D03*
X-1306850Y-95000D03*
X-1300350Y-88500D03*
X-1302400Y-84100D03*
X-1297995Y-58405D03*
X-1298400Y-63200D03*
X-1298780Y-52200D03*
X-1298000Y-41200D03*
X-1298700Y-35700D03*
X-1298800Y-30200D03*
X-1295400Y-13400D03*
X-1307500Y7000D03*
X-1295000Y14500D03*
X-1270000D03*
X-1257500Y-57500D03*
X-1245000Y-70000D03*
X-1232500Y-57500D03*
Y-45000D03*
X-1245000D03*
Y-20000D03*
Y14500D03*
X-1220000D03*
X-1199500Y5400D03*
X-1191200Y-40500D03*
X-1191000Y-46500D03*
X-1191500Y-34000D03*
X-1191900Y-29500D03*
X-1190800Y-23450D03*
X-1191000Y-18250D03*
X-1191200Y-12128D03*
X-1192359Y-5800D03*
X-1191500Y0D03*
X-1195000Y14500D03*
X-1172500Y-44000D03*
X-1173200Y-49700D03*
X-1178900Y-46700D03*
X-1179000Y-40500D03*
X-1172500Y-38500D03*
X-1178950Y-23250D03*
X-1171800Y-26950D03*
X-1178800Y-34800D03*
X-1177800Y-12100D03*
X-1172000Y-10750D03*
X-1171500Y-21750D03*
X-1171800Y-16250D03*
X-1178800Y-5800D03*
X-1172100Y-5400D03*
X-1170000Y14500D03*
X-1160000Y-38500D03*
X-1159700Y-43900D03*
X-1160150Y-26750D03*
X-1159800Y-33100D03*
X-1158700Y-16250D03*
X-1159700Y-5750D03*
X-1137500Y-2500D03*
X-1145000Y14500D03*
X-1126000Y-15000D03*
X-1120000Y14500D03*
X-1111500Y-2500D03*
X-1100000Y-15000D03*
X-1095000Y14500D03*
X-1056900Y-56300D03*
X-1062000Y-29200D03*
X-1061900Y-5200D03*
X-1044300Y-47661D03*
X-1051200Y-44100D03*
X-1054900Y-29800D03*
X-1045400Y-38000D03*
X-1051400Y-26000D03*
X-1047289Y-26300D03*
X-1041300Y-10100D03*
Y-16500D03*
X-1054600Y-5100D03*
X-1050811Y2600D03*
X-1047300Y-2700D03*
X-1032500Y14500D03*
X-1012500Y-7500D03*
X-1007500Y14500D03*
X-983000Y-7500D03*
X-982500Y14500D03*
X-957500Y-7500D03*
Y14500D03*
X-932500Y-7500D03*
Y14500D03*
X-922500Y-170000D03*
Y-120000D03*
Y-95000D03*
Y-70000D03*
Y-45000D03*
Y-20000D03*
Y5000D03*
X-910000Y-159500D03*
Y-132500D03*
Y-107500D03*
Y-82500D03*
Y-57500D03*
Y-7500D03*
X-909500Y14500D03*
X-897500Y-170000D03*
X-885000Y-159500D03*
Y-132500D03*
Y-107500D03*
X-897500Y-95000D03*
X-885000Y-82500D03*
X-897500Y-70000D03*
X-885000Y-57500D03*
X-897500Y-45000D03*
X-885000Y-7500D03*
X-897500Y-20000D03*
Y5000D03*
X-885000Y14500D03*
X-872500Y-170000D03*
Y-95000D03*
Y-70000D03*
Y-45000D03*
Y-20000D03*
Y5000D03*
X-860000Y-159500D03*
Y-132500D03*
Y-107500D03*
Y-82500D03*
Y-57500D03*
Y-7500D03*
Y14500D03*
X-847500Y-170000D03*
Y-95000D03*
Y-70000D03*
Y-45000D03*
Y-20000D03*
Y5000D03*
X-822500Y-170000D03*
X-835000Y-159500D03*
X-822500Y-145000D03*
X-835000Y-132500D03*
X-822500Y-120000D03*
X-835000Y-107500D03*
X-822500Y-95000D03*
X-835000Y-82500D03*
X-822500Y-70000D03*
X-835000Y-57500D03*
X-822500Y-45000D03*
Y-20000D03*
Y5000D03*
X-835500Y14500D03*
X-810000Y-170000D03*
Y-157500D03*
Y-145000D03*
Y-132500D03*
Y-120000D03*
Y-70000D03*
Y-57500D03*
Y-45000D03*
Y-7500D03*
Y14500D03*
X-797500Y-120000D03*
Y-70000D03*
Y-57500D03*
Y-45000D03*
Y-20000D03*
Y5000D03*
X-785500Y-120000D03*
X-785000Y-70000D03*
Y-57500D03*
Y-45000D03*
Y-7500D03*
Y14500D03*
X-772500Y-170000D03*
Y-145000D03*
X-760000Y-132500D03*
X-772500Y-120000D03*
X-760000Y-107500D03*
X-772500Y-95000D03*
X-760000Y-82500D03*
X-772500Y-70000D03*
X-760000Y-57500D03*
X-772500Y-45000D03*
X-760000Y-7500D03*
X-772500Y-20000D03*
Y5000D03*
X-760000Y14500D03*
X-747500Y-45000D03*
Y-20000D03*
Y5000D03*
X-735000Y-57500D03*
Y-7500D03*
Y14500D03*
X-722500Y-45000D03*
Y-20000D03*
Y5000D03*
X-697500Y-45000D03*
Y-20000D03*
X-710000Y-7500D03*
X-697500Y5000D03*
X-710000Y14500D03*
X-685000Y-7500D03*
Y14500D03*
X-672500Y-45000D03*
Y-20000D03*
Y5000D03*
X-655500Y-37500D03*
Y-12500D03*
Y-500D03*
X-660000Y14500D03*
X-632500D03*
X-616000Y-37500D03*
X-630000Y-25500D03*
Y-12500D03*
X-616000D03*
Y14500D03*
X-602500Y-37500D03*
Y-12500D03*
Y12500D03*
X-590000Y-25000D03*
Y0D03*
X-577500Y-152500D03*
Y-127500D03*
Y-37500D03*
Y-12500D03*
Y12500D03*
X-565000Y-165000D03*
Y-140000D03*
Y-65000D03*
Y-25000D03*
Y0D03*
X-540000Y-165000D03*
X-552500Y-177500D03*
Y-152500D03*
X-540000Y-140000D03*
Y-115000D03*
Y-90000D03*
Y-65000D03*
Y-25000D03*
X-552500Y-37500D03*
Y-12500D03*
X-540000Y0D03*
X-552500Y12500D03*
X-527500Y-177500D03*
Y-152500D03*
Y-127500D03*
Y-102500D03*
Y-77500D03*
Y-37500D03*
Y-12500D03*
Y12500D03*
X-515000Y-165000D03*
Y-140000D03*
Y-115000D03*
Y-90000D03*
Y-65000D03*
Y-25000D03*
Y0D03*
X-502500Y-102500D03*
X-490000Y-90000D03*
X-502500Y-77500D03*
Y-37500D03*
Y-12500D03*
X-490000Y0D03*
X-502500Y12500D03*
X-486421Y-26159D03*
X-477500Y-37500D03*
Y12500D03*
X-465000Y-25000D03*
X-461441Y6559D03*
X-456240Y-82020D03*
X-454421Y-26959D03*
X-443941Y6559D03*
X-448600Y-5900D03*
X-452500Y12500D03*
X-432118Y-87082D03*
X-436771Y-92400D03*
X-427500Y12500D03*
X-424600Y-14400D03*
X-1124700Y-180000D03*
X-1095600Y-179600D03*
X-442800Y-46600D03*
X-441959Y-68600D03*
X-429000Y-57600D03*
X-430700Y-63100D03*
X-430180Y-52100D03*
X-429400Y-41100D03*
X-430400Y-35600D03*
X-386500Y-56500D03*
Y-44000D03*
Y-31500D03*
Y-19000D03*
Y-5500D03*
X-374000Y-44000D03*
Y-31500D03*
Y-19000D03*
X-361500Y-44000D03*
X-348000D03*
Y-31500D03*
X-361500D03*
Y-19000D03*
X-348000D03*
X-336000Y-28000D03*
Y-15500D03*
X-321800Y-7300D03*
X-309400Y-25100D03*
X-308500Y-36400D03*
X-308800Y-7400D03*
X-302500Y-15200D03*
X-307900Y-13628D03*
X-289500Y-32500D03*
X-290800Y-26000D03*
X-290300Y-4400D03*
X-255500Y-25500D03*
X-268000Y-13000D03*
X-255500D03*
Y-500D03*
X-268000D03*
X-243000Y-40500D03*
Y-25500D03*
Y-13000D03*
Y-500D03*
X-230000Y-13500D03*
X-230500Y-500D03*
X-190300Y-28900D03*
Y-4200D03*
X-179800Y-43500D03*
X-182900Y-29800D03*
X-176350Y-27200D03*
X-183200Y-4600D03*
X-175100Y-1800D03*
G54D33*
X-1282480Y-130157D03*
Y-94724D03*
Y-59291D03*
Y-23858D03*
X-1207677Y-77008D03*
Y-41575D03*
Y-6142D03*
X-412402Y-59291D03*
X-337598Y-41575D03*
Y-6142D03*
G54D35*
X-1025000Y1459D03*
X-981693D03*
X-938386D03*
G54D37*
X-793728Y-153976D03*
Y-146102D03*
G54D32*
X-1327756Y-175039D03*
Y-167165D03*
Y-159291D03*
Y-143543D03*
Y-135669D03*
Y-127795D03*
X-1319882Y-175039D03*
Y-167165D03*
Y-159291D03*
Y-135669D03*
Y-127795D03*
X-793728Y-161850D03*
Y-138228D03*
X-457677Y-175039D03*
Y-167165D03*
Y-159291D03*
Y-143543D03*
Y-135669D03*
Y-127795D03*
X-449803Y-175039D03*
Y-167165D03*
Y-159291D03*
Y-135669D03*
Y-127795D03*
G54D29*
X-1278150Y-142362D03*
G54D38*
X-1085138Y-132520D03*
Y-112835D03*
Y-94331D03*
G54D34*
X-1141240Y-24252D03*
X-1118917Y-4567D03*
X-1085138Y-43937D03*
Y-4567D03*
X-806854Y-99635D03*
X-785200D03*
X-271161Y-24252D03*
X-248839Y-4567D03*
X-215059Y-83307D03*
Y-43937D03*
Y-4567D03*
G54D36*
X-806854Y-83100D03*
X-785200D03*
G54D30*
X-1410000Y0D03*
G54D31*
X-486810Y-118937D03*
%LPD*%
G75*
G54D10*
X-1615984Y-134488D03*
Y-128976D03*
Y-123465D03*
Y-117953D03*
X-1608110Y-128583D03*
Y-123071D03*
X-1615984Y-106929D03*
Y-101417D03*
X-1600236D03*
Y-106929D03*
X-1592362Y-106535D03*
Y-112047D03*
X-1584488Y-101417D03*
Y-106929D03*
X-1576614Y-106535D03*
Y-112047D03*
X-1568740Y-101417D03*
Y-106929D03*
X-1560866Y-106535D03*
Y-112047D03*
X-1552992Y-101417D03*
Y-106929D03*
X-1545118Y-106535D03*
Y-112047D03*
X-1197008Y-134882D03*
Y-140394D03*
X-1181260Y-167953D03*
Y-173465D03*
X-1165512Y-167953D03*
Y-173465D03*
X-1157638Y-173071D03*
Y-178583D03*
X-1014488Y-167953D03*
Y-173465D03*
Y-151417D03*
Y-156929D03*
Y-134882D03*
Y-140394D03*
X-998740Y-151417D03*
Y-156929D03*
X-1006614Y-140000D03*
Y-145512D03*
X-982992Y-167953D03*
Y-173465D03*
Y-151417D03*
Y-156929D03*
X-990866Y-140000D03*
Y-145512D03*
X-975118Y-173071D03*
Y-178583D03*
X-730157Y-140000D03*
X-738032Y-128583D03*
Y-123071D03*
X-730157Y-101417D03*
Y-106929D03*
X-722283Y-106535D03*
Y-112047D03*
X-714409Y-101417D03*
Y-106929D03*
X-706535Y-106535D03*
Y-112047D03*
X-698661Y-101417D03*
Y-106929D03*
X-682913Y-101417D03*
X-690787Y-106535D03*
X-682913Y-106929D03*
X-690787Y-112047D03*
X-675039Y-106535D03*
Y-112047D03*
X-326929Y-134882D03*
Y-140394D03*
X-311181Y-167953D03*
Y-173465D03*
X-295433Y-167953D03*
Y-173465D03*
X-287559Y-173071D03*
Y-178583D03*
X-144409Y-167953D03*
Y-173465D03*
Y-151417D03*
Y-156929D03*
Y-134882D03*
Y-140394D03*
X-128661Y-151417D03*
Y-156929D03*
X-136535Y-140000D03*
Y-145512D03*
X-112913Y-167953D03*
Y-173465D03*
Y-151417D03*
Y-156929D03*
X-120787Y-140000D03*
Y-145512D03*
X-105039Y-173071D03*
Y-178583D03*
G54D20*
G01X-1185925Y-592500D02*
X-1178575Y-577500D01*
G01X-1185925D02*
X-1178575Y-592500D01*
G01X-1168050D02*
X-1166825Y-592250D01*
X-1165425Y-591500D01*
X-1164550Y-590250D01*
X-1164200Y-588500D01*
X-1164550Y-586750D01*
X-1165600Y-585250D01*
X-1167175Y-584500D01*
X-1168925D01*
X-1169975Y-584000D01*
X-1170850Y-582750D01*
X-1171200Y-581000D01*
X-1170675Y-579250D01*
X-1169450Y-578000D01*
X-1168050Y-577500D01*
X-1166650Y-578000D01*
X-1165425Y-579250D01*
X-1164900Y-581000D01*
X-1165250Y-582750D01*
X-1166125Y-584000D01*
X-1167175Y-584500D01*
X-1168925D01*
X-1170500Y-585250D01*
X-1171550Y-586750D01*
X-1171900Y-588500D01*
X-1171550Y-590250D01*
X-1170675Y-591500D01*
X-1169275Y-592250D01*
X-1168050Y-592500D01*
G01X-1153850D02*
X-1152625Y-592250D01*
X-1151225Y-591500D01*
X-1150350Y-590250D01*
X-1150000Y-588500D01*
X-1150350Y-586750D01*
X-1151400Y-585250D01*
X-1152975Y-584500D01*
X-1154725D01*
X-1155775Y-584000D01*
X-1156650Y-582750D01*
X-1157000Y-581000D01*
X-1156475Y-579250D01*
X-1155250Y-578000D01*
X-1153850Y-577500D01*
X-1152450Y-578000D01*
X-1151225Y-579250D01*
X-1150700Y-581000D01*
X-1151050Y-582750D01*
X-1151925Y-584000D01*
X-1152975Y-584500D01*
X-1154725D01*
X-1156300Y-585250D01*
X-1157350Y-586750D01*
X-1157700Y-588500D01*
X-1157350Y-590250D01*
X-1156475Y-591500D01*
X-1155075Y-592250D01*
X-1153850Y-592500D01*
G01X-1140000D02*
X-1139650Y-589250D01*
X-1139125Y-586500D01*
X-1138425Y-584000D01*
X-1137550Y-581250D01*
X-1136150Y-577500D01*
X-1143150D01*
G01X-1129300Y-590250D02*
X-1128250Y-591500D01*
X-1127025Y-592250D01*
X-1125450Y-592500D01*
X-1123875Y-592000D01*
X-1122650Y-591000D01*
X-1121775Y-589250D01*
X-1121600Y-587250D01*
X-1121950Y-585250D01*
X-1122825Y-584000D01*
X-1124050Y-583000D01*
X-1125275Y-582750D01*
X-1126500Y-583000D01*
X-1128075Y-584000D01*
X-1127550Y-577500D01*
X-1122825D01*
G01X-1111600Y-592500D02*
X-1111250Y-589250D01*
X-1110725Y-586500D01*
X-1110025Y-584000D01*
X-1109150Y-581250D01*
X-1107750Y-577500D01*
X-1114750D01*
G01X-1097050Y-592500D02*
Y-577500D01*
X-1099150Y-580500D01*
G01Y-592500D02*
X-1094950D01*
G01X-1085125Y-587500D02*
X-1080575D01*
G01X-1068650Y-577500D02*
X-1070050Y-578000D01*
X-1071100Y-579250D01*
X-1071800Y-580750D01*
X-1072325Y-582750D01*
X-1072500Y-585000D01*
X-1072325Y-587250D01*
X-1071800Y-589250D01*
X-1071100Y-590750D01*
X-1070050Y-592000D01*
X-1068650Y-592500D01*
X-1067250Y-592000D01*
X-1066200Y-590750D01*
X-1065500Y-589250D01*
X-1064975Y-587250D01*
X-1064800Y-585000D01*
X-1064975Y-582750D01*
X-1065500Y-580750D01*
X-1066200Y-579250D01*
X-1067250Y-578000D01*
X-1068650Y-577500D01*
G01X-1054450D02*
X-1055850Y-578000D01*
X-1056900Y-579250D01*
X-1057600Y-580750D01*
X-1058125Y-582750D01*
X-1058300Y-585000D01*
X-1058125Y-587250D01*
X-1057600Y-589250D01*
X-1056900Y-590750D01*
X-1055850Y-592000D01*
X-1054450Y-592500D01*
X-1053050Y-592000D01*
X-1052000Y-590750D01*
X-1051300Y-589250D01*
X-1050775Y-587250D01*
X-1050600Y-585000D01*
X-1050775Y-582750D01*
X-1051300Y-580750D01*
X-1052000Y-579250D01*
X-1053050Y-578000D01*
X-1054450Y-577500D01*
G01X-1044100Y-590250D02*
X-1043050Y-591500D01*
X-1041825Y-592250D01*
X-1040250Y-592500D01*
X-1038675Y-592000D01*
X-1037450Y-591000D01*
X-1036575Y-589250D01*
X-1036400Y-587250D01*
X-1036750Y-585250D01*
X-1037625Y-584000D01*
X-1038850Y-583000D01*
X-1040075Y-582750D01*
X-1041300Y-583000D01*
X-1042875Y-584000D01*
X-1042350Y-577500D01*
X-1037625D01*
G01X-911875Y-592500D02*
X-907500Y-577500D01*
X-903125Y-592500D01*
G01X-904700Y-587250D02*
X-910300D01*
G01X-810781Y-87027D02*
X-806854Y-83100D01*
G01D02*
X-802927Y-79173D01*
G01X-810781D02*
X-806854Y-83100D01*
G01D02*
X-802927Y-87027D01*
G01X-789127D02*
X-785200Y-83100D01*
G01X-789127Y-79173D02*
X-785200Y-83100D01*
G01D02*
X-781273Y-87027D01*
G01X-785200Y-83100D02*
X-781273Y-79173D01*
G54D11*
X-1615000Y-37500D03*
Y-27500D03*
Y-32500D03*
X-1610000Y-37500D03*
Y-32500D03*
Y-27500D03*
X-1600000Y-37500D03*
Y-27500D03*
Y-32500D03*
X-1605000Y-37500D03*
Y-32500D03*
Y-27500D03*
X-1595000Y-37500D03*
Y-32500D03*
Y-27500D03*
X-1580000Y-42500D03*
Y-47500D03*
X-1585000Y-42500D03*
Y-47500D03*
X-1590000D03*
Y-42500D03*
X-1580000Y-27500D03*
Y-32500D03*
Y-37500D03*
X-1585000Y-32500D03*
Y-27500D03*
Y-37500D03*
X-1590000D03*
Y-32500D03*
Y-27500D03*
X-1565000Y-42500D03*
Y-47500D03*
X-1575000Y-42500D03*
Y-47500D03*
X-1570000Y-42500D03*
Y-47500D03*
X-1565000Y-27500D03*
Y-32500D03*
Y-37500D03*
X-1575000Y-27500D03*
Y-32500D03*
Y-37500D03*
X-1570000Y-32500D03*
Y-27500D03*
Y-37500D03*
X-1555000Y-47500D03*
Y-42500D03*
X-1550000Y-47500D03*
Y-42500D03*
X-1560000D03*
Y-47500D03*
X-1545000D03*
Y-42500D03*
Y-37500D03*
Y-32500D03*
Y-27500D03*
X-1555000Y-37500D03*
Y-32500D03*
Y-27500D03*
X-1550000Y-37500D03*
Y-32500D03*
Y-27500D03*
X-1560000D03*
Y-32500D03*
Y-37500D03*
X-1535000Y-42500D03*
Y-47500D03*
X-1540000Y-42500D03*
Y-47500D03*
Y-37500D03*
Y-32500D03*
X-1535000Y-37500D03*
Y-32500D03*
X-1497000Y-81700D03*
X-1496693Y-76890D03*
Y-71890D03*
X-1486693D03*
X-1491693D03*
X-1466693Y-151890D03*
Y-156890D03*
Y-136890D03*
Y-131890D03*
Y-111890D03*
Y-116890D03*
Y-91890D03*
Y-96890D03*
X-1461693Y-166890D03*
Y-161890D03*
Y-141890D03*
Y-146890D03*
Y-121890D03*
Y-126890D03*
Y-101890D03*
Y-106890D03*
Y-86890D03*
Y-81890D03*
X-1450000Y-175000D03*
X-1437500Y-162500D03*
X-1450000Y-150000D03*
Y-125000D03*
X-1443500Y-94000D03*
X-1450000Y-100000D03*
X-1434892Y-40389D03*
Y-50389D03*
Y-45389D03*
Y-35389D03*
X-1425000Y-175000D03*
X-1424500Y-100000D03*
X-1425000Y-87500D03*
Y-62500D03*
X-1419892Y-50389D03*
Y-40389D03*
Y-45389D03*
X-1427392Y-50389D03*
Y-45389D03*
Y-40389D03*
X-1419892Y-35389D03*
X-1427392D03*
X-1432000Y-18000D03*
X-1412500Y-162500D03*
X-1412000Y-87000D03*
X-1412500Y-75000D03*
X-1404892Y-50389D03*
Y-45389D03*
Y-40389D03*
X-1412392Y-50389D03*
Y-45389D03*
Y-40389D03*
X-1404892Y-35389D03*
X-1412392D03*
X-1407000Y-18000D03*
X-1407500Y14500D03*
X-1400000Y-175000D03*
X-1387500Y-162500D03*
X-1400000Y-150000D03*
X-1387500Y-137500D03*
X-1400000Y-125000D03*
X-1387500Y-112500D03*
X-1400500Y-87000D03*
X-1391000Y-96500D03*
X-1387500Y-75000D03*
X-1400000Y-62500D03*
X-1389892Y-40389D03*
Y-45389D03*
Y-50389D03*
X-1397392Y-40389D03*
Y-45389D03*
Y-50389D03*
X-1389892Y-35389D03*
X-1397392D03*
X-1395000Y-8000D03*
X-1375000Y-62500D03*
X-1382392Y-40389D03*
Y-45389D03*
Y-50389D03*
Y-35389D03*
X-1382500Y-18000D03*
Y-500D03*
Y14500D03*
X-1362500Y-75000D03*
X-1370000Y-8000D03*
X-1357500Y-500D03*
X-1370000Y7000D03*
X-1357500Y14500D03*
X-1350000Y-62500D03*
X-1345000Y-8000D03*
Y7000D03*
X-1335400Y-75000D03*
Y-37600D03*
X-1332500Y-500D03*
Y14500D03*
X-1322228Y-88400D03*
X-1316728Y-89200D03*
X-1320000Y7000D03*
X-1293500Y-80000D03*
X-1307500Y14500D03*
X-1282500D03*
X-1276860Y-178030D03*
X-1245710Y-189905D03*
Y-186705D03*
X-1247979Y-177933D03*
X-1246390Y-153490D03*
X-1257500Y-45000D03*
Y-20000D03*
Y14500D03*
X-1232340Y-185380D03*
X-1235540D03*
X-1241142Y-178998D03*
X-1244291Y-177998D03*
X-1230093Y-134350D03*
X-1233293D03*
X-1232500Y-20000D03*
Y14500D03*
X-1209420Y-167360D03*
X-1206220D03*
X-1199500Y-3000D03*
X-1207500Y14500D03*
X-1182500D03*
X-1151500Y-15000D03*
X-1157500Y14500D03*
X-1137500Y-15000D03*
X-1134579Y-179850D03*
X-1126000Y-2500D03*
X-1132500Y14500D03*
X-1113328Y-182209D03*
X-1107828Y-182300D03*
X-1114979Y-170700D03*
X-1106979D03*
X-1114500Y-129000D03*
X-1110500D03*
X-1107700Y-73400D03*
Y-63100D03*
X-1107800Y-68200D03*
X-1111500Y-15000D03*
X-1107500Y14500D03*
X-1099400Y-90200D03*
X-1093400D03*
X-1100000Y-2500D03*
X-1084600Y-179850D03*
X-1073000Y-90300D03*
X-1082500Y14500D03*
X-1070000D03*
X-1045000D03*
X-1020000D03*
X-997500Y-7500D03*
X-995000Y14500D03*
X-970000Y-7500D03*
Y14500D03*
X-945000Y-7500D03*
Y14500D03*
X-922500Y-159500D03*
Y-132500D03*
Y-107500D03*
Y-82500D03*
Y-57500D03*
Y-7500D03*
X-922000Y14500D03*
X-910000Y-170000D03*
Y-95000D03*
Y-70000D03*
Y-45000D03*
Y-20000D03*
Y5000D03*
X-885000Y-170000D03*
X-897500Y-159500D03*
Y-132500D03*
Y-107500D03*
X-885000Y-95000D03*
X-897500Y-82500D03*
X-885000Y-70000D03*
X-897500Y-57500D03*
X-885000Y-45000D03*
Y-20000D03*
X-897500Y-7500D03*
X-885000Y5000D03*
X-897500Y14500D03*
X-872500Y-159500D03*
Y-132500D03*
Y-107500D03*
Y-82500D03*
Y-57500D03*
Y-7500D03*
Y14500D03*
X-860000Y-170000D03*
Y-95000D03*
Y-70000D03*
Y-45000D03*
Y-20000D03*
Y5000D03*
X-847500Y-159500D03*
Y-132500D03*
Y-107500D03*
Y-82500D03*
Y-57500D03*
Y-7500D03*
X-848000Y14500D03*
X-822500Y-159500D03*
Y-132500D03*
X-835000Y-120000D03*
X-822500Y-107500D03*
X-835000Y-95000D03*
X-822500Y-82500D03*
X-835000Y-70000D03*
X-822500Y-57500D03*
X-835000Y-45000D03*
X-822500Y-7500D03*
X-835000Y-20000D03*
X-822500Y14500D03*
X-810000Y-20000D03*
Y5000D03*
X-797500Y-7500D03*
Y14500D03*
X-785000Y-20000D03*
Y5000D03*
X-760000Y-145000D03*
X-772500Y-132500D03*
X-760000Y-120000D03*
X-772500Y-107500D03*
X-760000Y-95000D03*
X-772500Y-82500D03*
X-760000Y-70000D03*
X-772500Y-57500D03*
X-760000Y-45000D03*
Y-20000D03*
X-772500Y-7500D03*
X-760000Y5000D03*
X-772500Y14500D03*
X-747500Y-57500D03*
Y-7500D03*
Y14500D03*
X-735000Y-45000D03*
Y-20000D03*
Y5000D03*
X-722500Y-57500D03*
Y-7500D03*
Y14500D03*
X-710000Y-45000D03*
X-697500Y-7500D03*
X-710000Y-20000D03*
Y5000D03*
X-697500Y14500D03*
X-685000Y-45000D03*
Y-20000D03*
Y5000D03*
X-672500Y-7500D03*
Y14500D03*
X-655500Y-25500D03*
X-642500D03*
Y-37500D03*
Y-12500D03*
X-645000Y14500D03*
X-630000Y-37500D03*
X-616000Y-25500D03*
X-602500Y-25000D03*
Y0D03*
X-591614Y-166890D03*
X-591200Y-179700D03*
X-596614Y-151890D03*
X-591614Y-161890D03*
X-596614Y-156890D03*
X-591614Y-141890D03*
X-596614Y-136890D03*
X-591614Y-146890D03*
Y-121890D03*
X-596614Y-131890D03*
X-591614Y-126890D03*
X-596614Y-111890D03*
X-591614Y-101890D03*
X-596614Y-116890D03*
X-591614Y-106890D03*
Y-86890D03*
X-596614Y-91890D03*
Y-96890D03*
X-591614Y-81890D03*
X-590000Y-37500D03*
Y-12500D03*
Y12500D03*
X-577500Y-165000D03*
Y-140000D03*
Y-115000D03*
Y-65000D03*
Y-25000D03*
Y0D03*
X-565000Y-177500D03*
Y-152500D03*
Y-37500D03*
Y-12500D03*
Y12500D03*
X-540000Y-177500D03*
X-552500Y-165000D03*
X-540000Y-152500D03*
X-552500Y-140000D03*
X-540000Y-127500D03*
Y-102500D03*
Y-77500D03*
X-552500Y-65000D03*
Y-25000D03*
X-540000Y-37500D03*
Y-12500D03*
X-552500Y0D03*
X-540000Y12500D03*
X-527500Y-165000D03*
Y-140000D03*
Y-115000D03*
Y-90000D03*
Y-65000D03*
Y-25000D03*
Y0D03*
X-515000Y-177500D03*
Y-152500D03*
Y-127500D03*
Y-102500D03*
Y-77500D03*
Y-37500D03*
Y-12500D03*
Y12500D03*
X-490000Y-102500D03*
X-502500Y-90000D03*
X-490000Y-77500D03*
X-502500Y-65000D03*
X-490000Y-37500D03*
X-502500Y-25000D03*
X-490000Y-12500D03*
X-502500Y0D03*
X-490000Y12500D03*
X-477500Y-25000D03*
Y0D03*
X-462000Y-73500D03*
X-465000Y-37500D03*
Y12500D03*
X-453628Y-88300D03*
X-448128Y-88800D03*
X-449100Y-60841D03*
X-449000Y6500D03*
X-441959Y-74100D03*
Y-63100D03*
Y-57600D03*
Y-41100D03*
Y-52100D03*
Y-35600D03*
X-431000Y6500D03*
X-440000Y12500D03*
X-424500Y-26500D03*
X-405540Y-183080D03*
Y-179630D03*
X-375631Y-189905D03*
Y-186705D03*
X-365461Y-185380D03*
X-377900Y-177933D03*
X-367913Y-179850D03*
X-362261Y-185380D03*
X-360014Y-134350D03*
X-363214D03*
X-339341Y-167360D03*
X-336141D03*
X-321600Y-113500D03*
X-316500D03*
X-322400Y-31000D03*
X-321300Y-24950D03*
X-321700Y-13628D03*
X-321859Y-1500D03*
X-303200Y-43300D03*
Y-48800D03*
X-302300Y-25950D03*
X-302900Y-37900D03*
X-302300Y-4450D03*
X-290400Y-43200D03*
X-290700Y-9750D03*
X-274400Y-178200D03*
X-278100D03*
X-244900Y-170700D03*
X-244300Y-129300D03*
X-240300D03*
X-236900Y-170700D03*
X-196900Y-176500D03*
X-201600Y-176600D03*
X-206100D03*
X-179811Y-21300D03*
X-179011Y4500D03*
X-173800Y-47300D03*
X-173200Y-52400D03*
X-170200Y-34470D03*
X-170500Y-10000D03*
X-170300Y-16500D03*
G54D21*
G01X-1200000Y-560000D02*
X-890000D01*
G01Y-520000D02*
X-1200000D01*
G01X-575000Y-480000D02*
X-1200000D01*
G01X-927500Y-560000D02*
Y-600000D01*
G01X-915000Y-440000D02*
Y-480000D01*
G01X-890000D02*
Y-600000D01*
G01X-870000Y-440000D02*
Y-480000D01*
G01X-680000D02*
Y-440000D01*
G01X-1200000Y-600000D02*
X-575000D01*
Y-440000D01*
X-1200000D01*
Y-600000D01*
G54D12*
X-1356889Y-167165D03*
Y-118937D03*
X-1051613Y-167165D03*
Y-118937D03*
X-486810Y-167165D03*
Y-118937D03*
X-181534Y-167165D03*
Y-118937D03*
G54D22*
G01X-1608110Y-123071D02*
X-1605929Y-125252D01*
X-1605429D01*
X-1604800Y-124622D01*
Y-89000D01*
X-1582450Y-66650D01*
X-1523650D01*
X-1504630Y-85670D01*
X-1495850D01*
X-1488950Y-78770D01*
X-1470074D01*
X-1468600Y-80244D01*
Y-83364D01*
X-1468149Y-83815D01*
X-1463618D01*
X-1461693Y-81890D01*
G01X-1608110Y-128583D02*
X-1605929Y-126402D01*
X-1604953D01*
X-1603650Y-125099D01*
Y-89476D01*
X-1581974Y-67800D01*
X-1524126D01*
X-1505106Y-86820D01*
X-1495374D01*
X-1488474Y-79920D01*
X-1470550D01*
X-1469750Y-80720D01*
Y-83840D01*
X-1468625Y-84965D01*
X-1463618D01*
X-1461693Y-86890D01*
G01X-1466693Y-91890D02*
X-1468618Y-93815D01*
X-1473149D01*
X-1473600Y-93364D01*
Y-90244D01*
X-1475074Y-88770D01*
X-1493026D01*
X-1496496Y-92240D01*
X-1504960D01*
X-1526350Y-70850D01*
X-1579476D01*
X-1596815Y-88188D01*
Y-102814D01*
X-1597599Y-103598D01*
X-1598055D01*
X-1600236Y-101417D01*
G01X-1466693Y-96890D02*
X-1468618Y-94965D01*
X-1473625D01*
X-1474750Y-93840D01*
Y-90720D01*
X-1475550Y-89920D01*
X-1492550D01*
X-1496020Y-93390D01*
X-1505436D01*
X-1526826Y-72000D01*
X-1579000D01*
X-1595665Y-88665D01*
Y-103290D01*
X-1597123Y-104748D01*
X-1598055D01*
X-1600236Y-106929D01*
G01X-1584488Y-101417D02*
X-1582307Y-103598D01*
X-1581370D01*
X-1581150Y-103379D01*
Y-93024D01*
X-1567176Y-79050D01*
X-1536050D01*
X-1523426Y-91674D01*
X-1517200D01*
X-1502584Y-106290D01*
X-1494660D01*
X-1492180Y-108770D01*
X-1475074D01*
X-1473600Y-110244D01*
Y-113364D01*
X-1473149Y-113815D01*
X-1468618D01*
X-1466693Y-111890D01*
G01X-1461693Y-101890D02*
X-1463618Y-103815D01*
X-1468149D01*
X-1468600Y-103364D01*
Y-100244D01*
X-1470074Y-98770D01*
X-1504230D01*
X-1528050Y-74950D01*
X-1573376D01*
X-1589050Y-90624D01*
Y-108410D01*
X-1589356Y-108716D01*
X-1590181D01*
X-1592362Y-106535D01*
G01X-1584488Y-106929D02*
X-1582307Y-104748D01*
X-1580893D01*
X-1580000Y-103855D01*
Y-93500D01*
X-1566700Y-80200D01*
X-1536526D01*
X-1523903Y-92824D01*
X-1517676D01*
X-1503060Y-107440D01*
X-1495136D01*
X-1492656Y-109920D01*
X-1475550D01*
X-1474750Y-110720D01*
Y-113840D01*
X-1473625Y-114965D01*
X-1468618D01*
X-1466693Y-116890D01*
G01X-1461693Y-106890D02*
X-1463618Y-104965D01*
X-1468625D01*
X-1469750Y-103840D01*
Y-100720D01*
X-1470550Y-99920D01*
X-1504706D01*
X-1528526Y-76100D01*
X-1572900D01*
X-1587900Y-91100D01*
Y-108887D01*
X-1588880Y-109866D01*
X-1590181D01*
X-1592362Y-112047D01*
G01X-1461693Y-121890D02*
X-1463618Y-123815D01*
X-1468149D01*
X-1468600Y-123364D01*
Y-120244D01*
X-1470074Y-118770D01*
X-1502330D01*
X-1537950Y-83150D01*
X-1563150D01*
X-1573250Y-93250D01*
Y-108274D01*
X-1573693Y-108716D01*
X-1574433D01*
X-1576614Y-106535D01*
G01X-1568740Y-101417D02*
X-1566559Y-103598D01*
X-1565970D01*
X-1565350Y-102978D01*
Y-93124D01*
X-1559576Y-87350D01*
X-1539750D01*
X-1524500Y-102600D01*
Y-106074D01*
X-1504294Y-126280D01*
X-1493310D01*
X-1490820Y-128770D01*
X-1475074D01*
X-1473600Y-130244D01*
Y-133364D01*
X-1473149Y-133815D01*
X-1468618D01*
X-1466693Y-131890D01*
G01X-1461693Y-126890D02*
X-1463618Y-124965D01*
X-1468625D01*
X-1469750Y-123840D01*
Y-120720D01*
X-1470550Y-119920D01*
X-1502806D01*
X-1538426Y-84300D01*
X-1562674D01*
X-1572100Y-93726D01*
Y-108750D01*
X-1573216Y-109866D01*
X-1574433D01*
X-1576614Y-112047D01*
G01X-1568740Y-106929D02*
X-1566559Y-104748D01*
X-1565494D01*
X-1564200Y-103454D01*
Y-93600D01*
X-1559100Y-88500D01*
X-1540226D01*
X-1525650Y-103076D01*
Y-106550D01*
X-1504770Y-127430D01*
X-1493786D01*
X-1491296Y-129920D01*
X-1475550D01*
X-1474750Y-130720D01*
Y-133840D01*
X-1473625Y-134965D01*
X-1468618D01*
X-1466693Y-136890D01*
G01X-1461693Y-141890D02*
X-1463618Y-143815D01*
X-1468149D01*
X-1468600Y-143364D01*
Y-140244D01*
X-1470074Y-138770D01*
X-1505530D01*
X-1529100Y-115200D01*
Y-104200D01*
X-1541850Y-91450D01*
X-1554850D01*
X-1557450Y-94050D01*
Y-108401D01*
X-1557765Y-108716D01*
X-1558685D01*
X-1560866Y-106535D01*
G01X-1552992Y-101417D02*
X-1550811Y-103598D01*
X-1550311D01*
X-1549811Y-103098D01*
Y-98460D01*
X-1547801Y-96450D01*
X-1543050D01*
X-1534250Y-105250D01*
Y-120150D01*
X-1508060Y-146340D01*
X-1493670D01*
X-1491240Y-148770D01*
X-1475074D01*
X-1473600Y-150244D01*
Y-153364D01*
X-1473149Y-153815D01*
X-1468618D01*
X-1466693Y-151890D01*
G01X-1461693Y-146890D02*
X-1463618Y-144965D01*
X-1468625D01*
X-1469750Y-143840D01*
Y-140720D01*
X-1470550Y-139920D01*
X-1506006D01*
X-1530250Y-115676D01*
Y-104676D01*
X-1542326Y-92600D01*
X-1554374D01*
X-1556300Y-94526D01*
Y-108878D01*
X-1557289Y-109866D01*
X-1558685D01*
X-1560866Y-112047D01*
G01X-1552992Y-106929D02*
X-1550811Y-104748D01*
X-1549835D01*
X-1548661Y-103575D01*
Y-98937D01*
X-1547325Y-97600D01*
X-1543526D01*
X-1535400Y-105726D01*
Y-120626D01*
X-1508536Y-147490D01*
X-1494146D01*
X-1491716Y-149920D01*
X-1475550D01*
X-1474750Y-150720D01*
Y-153840D01*
X-1473625Y-154965D01*
X-1468618D01*
X-1466693Y-156890D01*
G01X-1545118Y-106535D02*
X-1542937Y-108716D01*
X-1541961D01*
X-1539956Y-110721D01*
Y-130444D01*
X-1539224Y-131176D01*
X-1539223D01*
X-1538550Y-131850D01*
Y-161824D01*
X-1528774Y-171600D01*
X-1472220D01*
X-1469710Y-169090D01*
Y-165240D01*
X-1468285Y-163815D01*
X-1463618D01*
X-1461693Y-161890D01*
G01X-1545118Y-112047D02*
X-1542937Y-109866D01*
X-1542437D01*
X-1541106Y-111197D01*
Y-130920D01*
X-1539700Y-132326D01*
Y-162300D01*
X-1529250Y-172750D01*
X-1471744D01*
X-1468560Y-169566D01*
Y-165716D01*
X-1467808Y-164965D01*
X-1463618D01*
X-1461693Y-166890D01*
G01X-1007500Y-470000D02*
X-1006450Y-475000D01*
X-1005250Y-470000D01*
X-1004050Y-475000D01*
X-1003000Y-470000D01*
G01X-1001125Y-475000D02*
X-999250Y-470000D01*
X-997375Y-475000D01*
G01X-998050Y-473250D02*
X-1000450D01*
G01X-994825Y-474333D02*
X-994225Y-474750D01*
X-993550Y-475000D01*
X-992950D01*
X-992350Y-474750D01*
X-991900Y-474333D01*
X-991675Y-473750D01*
X-991825Y-473167D01*
X-992200Y-472667D01*
X-992875Y-472333D01*
X-993775Y-472167D01*
X-994300Y-471833D01*
X-994525Y-471250D01*
X-994375Y-470667D01*
X-994000Y-470250D01*
X-993475Y-470000D01*
X-992950D01*
X-992425Y-470167D01*
X-991975Y-470583D01*
G01X-988825Y-475000D02*
Y-470000D01*
G01X-985675D02*
Y-475000D01*
G01Y-472500D02*
X-988825D01*
G01X-976525Y-474417D02*
X-976000Y-474833D01*
X-975400Y-475000D01*
X-974800Y-474833D01*
X-974275Y-474333D01*
X-973900Y-473583D01*
X-973750Y-472833D01*
Y-471917D01*
X-973900Y-471167D01*
X-974275Y-470500D01*
X-974725Y-470167D01*
X-975250Y-470000D01*
X-975850Y-470167D01*
X-976300Y-470500D01*
X-976600Y-471000D01*
X-976750Y-471667D01*
X-976600Y-472250D01*
X-976225Y-472833D01*
X-975775Y-473167D01*
X-975250Y-473250D01*
X-974650Y-473083D01*
X-974200Y-472667D01*
X-973750Y-471917D01*
G01X-969250Y-475000D02*
X-968725Y-474917D01*
X-968125Y-474667D01*
X-967750Y-474250D01*
X-967600Y-473667D01*
X-967750Y-473083D01*
X-968200Y-472583D01*
X-968875Y-472333D01*
X-969625D01*
X-970075Y-472167D01*
X-970450Y-471750D01*
X-970600Y-471167D01*
X-970375Y-470583D01*
X-969850Y-470167D01*
X-969250Y-470000D01*
X-968650Y-470167D01*
X-968125Y-470583D01*
X-967900Y-471167D01*
X-968050Y-471750D01*
X-968425Y-472167D01*
X-968875Y-472333D01*
X-969625D01*
X-970300Y-472583D01*
X-970750Y-473083D01*
X-970900Y-473667D01*
X-970750Y-474250D01*
X-970375Y-474667D01*
X-969775Y-474917D01*
X-969250Y-475000D01*
G01X-963250Y-470000D02*
X-963850Y-470167D01*
X-964300Y-470583D01*
X-964600Y-471083D01*
X-964825Y-471750D01*
X-964900Y-472500D01*
X-964825Y-473250D01*
X-964600Y-473917D01*
X-964300Y-474417D01*
X-963850Y-474833D01*
X-963250Y-475000D01*
X-962650Y-474833D01*
X-962200Y-474417D01*
X-961900Y-473917D01*
X-961675Y-473250D01*
X-961600Y-472500D01*
X-961675Y-471750D01*
X-961900Y-471083D01*
X-962200Y-470583D01*
X-962650Y-470167D01*
X-963250Y-470000D01*
G01X-958900Y-474250D02*
X-958450Y-474667D01*
X-957925Y-474917D01*
X-957250Y-475000D01*
X-956575Y-474833D01*
X-956050Y-474500D01*
X-955675Y-473917D01*
X-955600Y-473250D01*
X-955750Y-472583D01*
X-956125Y-472167D01*
X-956650Y-471833D01*
X-957175Y-471750D01*
X-957700Y-471833D01*
X-958375Y-472167D01*
X-958150Y-470000D01*
X-956125D01*
G01X-952675Y-470833D02*
X-952225Y-470333D01*
X-951700Y-470083D01*
X-951100Y-470000D01*
X-950350Y-470167D01*
X-949825Y-470583D01*
X-949675Y-471083D01*
X-949750Y-471583D01*
X-950050Y-472000D01*
X-951550Y-472833D01*
X-952225Y-473417D01*
X-952675Y-474250D01*
X-952825Y-475000D01*
X-949675D01*
G01X-946225Y-473333D02*
X-944275D01*
G01X-940675Y-472917D02*
X-940150Y-472333D01*
X-939700Y-472000D01*
X-939100Y-471833D01*
X-938575Y-472000D01*
X-938200Y-472333D01*
X-937900Y-472833D01*
X-937825Y-473417D01*
X-937900Y-473917D01*
X-938200Y-474417D01*
X-938650Y-474833D01*
X-939175Y-475000D01*
X-939775Y-474833D01*
X-940300Y-474333D01*
X-940600Y-473583D01*
X-940675Y-472750D01*
X-940525Y-471667D01*
X-940300Y-471083D01*
X-939925Y-470500D01*
X-939400Y-470083D01*
X-938875Y-470000D01*
X-938350Y-470167D01*
X-937975Y-470583D01*
G01X-934900Y-474000D02*
X-934450Y-474583D01*
X-933850Y-474917D01*
X-933175Y-475000D01*
X-932575Y-474917D01*
X-931975Y-474500D01*
X-931600Y-474000D01*
X-931525Y-473500D01*
X-931675Y-472917D01*
X-932200Y-472500D01*
X-932725Y-472333D01*
X-933400D01*
G01X-932725D02*
X-932275Y-472083D01*
X-931900Y-471667D01*
X-931750Y-471167D01*
X-931900Y-470667D01*
X-932275Y-470250D01*
X-932950Y-470000D01*
X-933625Y-470083D01*
X-934300Y-470417D01*
G01X-928525Y-474417D02*
X-928000Y-474833D01*
X-927400Y-475000D01*
X-926800Y-474833D01*
X-926275Y-474333D01*
X-925900Y-473583D01*
X-925750Y-472833D01*
Y-471917D01*
X-925900Y-471167D01*
X-926275Y-470500D01*
X-926725Y-470167D01*
X-927250Y-470000D01*
X-927850Y-470167D01*
X-928300Y-470500D01*
X-928600Y-471000D01*
X-928750Y-471667D01*
X-928600Y-472250D01*
X-928225Y-472833D01*
X-927775Y-473167D01*
X-927250Y-473250D01*
X-926650Y-473083D01*
X-926200Y-472667D01*
X-925750Y-471917D01*
G01X-922525Y-474417D02*
X-922000Y-474833D01*
X-921400Y-475000D01*
X-920800Y-474833D01*
X-920275Y-474333D01*
X-919900Y-473583D01*
X-919750Y-472833D01*
Y-471917D01*
X-919900Y-471167D01*
X-920275Y-470500D01*
X-920725Y-470167D01*
X-921250Y-470000D01*
X-921850Y-470167D01*
X-922300Y-470500D01*
X-922600Y-471000D01*
X-922750Y-471667D01*
X-922600Y-472250D01*
X-922225Y-472833D01*
X-921775Y-473167D01*
X-921250Y-473250D01*
X-920650Y-473083D01*
X-920200Y-472667D01*
X-919750Y-471917D01*
G01X-1006750Y-465000D02*
Y-460000D01*
X-1004875D01*
X-1004275Y-460250D01*
X-1003900Y-460583D01*
X-1003750Y-461250D01*
X-1003900Y-461917D01*
X-1004350Y-462333D01*
X-1004875Y-462583D01*
X-1006750D01*
G01X-1004875D02*
X-1003750Y-465000D01*
G01X-997750D02*
X-1000750D01*
Y-460000D01*
X-997750D01*
G01X-998950Y-462417D02*
X-1000750D01*
G01X-994900Y-465000D02*
Y-460000D01*
X-993400D01*
X-992800Y-460250D01*
X-992350Y-460583D01*
X-991975Y-461083D01*
X-991675Y-461667D01*
X-991600Y-462500D01*
X-991675Y-463333D01*
X-991975Y-463917D01*
X-992350Y-464417D01*
X-992800Y-464750D01*
X-993400Y-465000D01*
X-994900D01*
G01X-989200D02*
Y-460000D01*
X-987250Y-464167D01*
X-985300Y-460000D01*
Y-465000D01*
G01X-981250D02*
X-981850Y-464917D01*
X-982375Y-464583D01*
X-982825Y-464083D01*
X-983125Y-463500D01*
X-983275Y-462833D01*
Y-462167D01*
X-983125Y-461500D01*
X-982825Y-460917D01*
X-982375Y-460417D01*
X-981850Y-460083D01*
X-981250Y-460000D01*
X-980650Y-460083D01*
X-980125Y-460417D01*
X-979675Y-460917D01*
X-979375Y-461500D01*
X-979225Y-462167D01*
Y-462833D01*
X-979375Y-463500D01*
X-979675Y-464083D01*
X-980125Y-464583D01*
X-980650Y-464917D01*
X-981250Y-465000D01*
G01X-976975D02*
Y-460000D01*
X-973525Y-465000D01*
Y-460000D01*
G01X-970900Y-465000D02*
Y-460000D01*
X-969400D01*
X-968800Y-460250D01*
X-968350Y-460583D01*
X-967975Y-461083D01*
X-967675Y-461667D01*
X-967600Y-462500D01*
X-967675Y-463333D01*
X-967975Y-463917D01*
X-968350Y-464417D01*
X-968800Y-464750D01*
X-969400Y-465000D01*
X-970900D01*
G01X-1005250Y-455000D02*
Y-450000D01*
X-1006150Y-451000D01*
G01Y-455000D02*
X-1004350D01*
G01X-995200D02*
Y-450000D01*
X-993250Y-454167D01*
X-991300Y-450000D01*
Y-455000D01*
G01X-988150Y-450000D02*
X-986350D01*
G01X-987250D02*
Y-455000D01*
G01X-988150D02*
X-986350D01*
G01X-979600Y-450417D02*
X-980050Y-450167D01*
X-980575Y-450000D01*
X-981175D01*
X-981850Y-450250D01*
X-982375Y-450667D01*
X-982750Y-451167D01*
X-983050Y-452000D01*
X-983125Y-452750D01*
X-982975Y-453500D01*
X-982750Y-454000D01*
X-982300Y-454500D01*
X-981775Y-454833D01*
X-981250Y-455000D01*
X-980725D01*
X-980200Y-454833D01*
X-979750Y-454583D01*
X-979375Y-454250D01*
G01X-976750Y-455000D02*
Y-450000D01*
X-974875D01*
X-974275Y-450250D01*
X-973900Y-450583D01*
X-973750Y-451250D01*
X-973900Y-451917D01*
X-974350Y-452333D01*
X-974875Y-452583D01*
X-976750D01*
G01X-974875D02*
X-973750Y-455000D01*
G01X-969250D02*
X-969850Y-454917D01*
X-970375Y-454583D01*
X-970825Y-454083D01*
X-971125Y-453500D01*
X-971275Y-452833D01*
Y-452167D01*
X-971125Y-451500D01*
X-970825Y-450917D01*
X-970375Y-450417D01*
X-969850Y-450083D01*
X-969250Y-450000D01*
X-968650Y-450083D01*
X-968125Y-450417D01*
X-967675Y-450917D01*
X-967375Y-451500D01*
X-967225Y-452167D01*
Y-452833D01*
X-967375Y-453500D01*
X-967675Y-454083D01*
X-968125Y-454583D01*
X-968650Y-454917D01*
X-969250Y-455000D01*
G01X-964825Y-454333D02*
X-964225Y-454750D01*
X-963550Y-455000D01*
X-962950D01*
X-962350Y-454750D01*
X-961900Y-454333D01*
X-961675Y-453750D01*
X-961825Y-453167D01*
X-962200Y-452667D01*
X-962875Y-452333D01*
X-963775Y-452167D01*
X-964300Y-451833D01*
X-964525Y-451250D01*
X-964375Y-450667D01*
X-964000Y-450250D01*
X-963475Y-450000D01*
X-962950D01*
X-962425Y-450167D01*
X-961975Y-450583D01*
G01X-957250Y-455000D02*
X-957850Y-454917D01*
X-958375Y-454583D01*
X-958825Y-454083D01*
X-959125Y-453500D01*
X-959275Y-452833D01*
Y-452167D01*
X-959125Y-451500D01*
X-958825Y-450917D01*
X-958375Y-450417D01*
X-957850Y-450083D01*
X-957250Y-450000D01*
X-956650Y-450083D01*
X-956125Y-450417D01*
X-955675Y-450917D01*
X-955375Y-451500D01*
X-955225Y-452167D01*
Y-452833D01*
X-955375Y-453500D01*
X-955675Y-454083D01*
X-956125Y-454583D01*
X-956650Y-454917D01*
X-957250Y-455000D01*
G01X-952675D02*
Y-450000D01*
X-949825D01*
G01X-950875Y-452417D02*
X-952675D01*
G01X-945250Y-450000D02*
Y-455000D01*
G01X-946975Y-450000D02*
X-943525D01*
G01X-935500D02*
X-934450Y-455000D01*
X-933250Y-450000D01*
X-932050Y-455000D01*
X-931000Y-450000D01*
G01X-929125Y-455000D02*
X-927250Y-450000D01*
X-925375Y-455000D01*
G01X-926050Y-453250D02*
X-928450D01*
G01X-921250Y-455000D02*
Y-452750D01*
X-922750Y-450000D01*
G01X-919750D02*
X-921250Y-452750D01*
G01X-738032Y-123071D02*
X-735851Y-125252D01*
X-735351D01*
X-734721Y-124622D01*
Y-89000D01*
X-712371Y-66650D01*
X-653571D01*
X-634551Y-85670D01*
X-625771D01*
X-618911Y-78810D01*
X-599955D01*
X-598521Y-80244D01*
Y-83364D01*
X-598070Y-83815D01*
X-593539D01*
X-591614Y-81890D01*
G01X-738032Y-128583D02*
X-735851Y-126402D01*
X-734874D01*
X-733571Y-125099D01*
Y-89476D01*
X-711895Y-67800D01*
X-654048D01*
X-635028Y-86820D01*
X-625295D01*
X-618435Y-79960D01*
X-600431D01*
X-599671Y-80720D01*
Y-83840D01*
X-598546Y-84965D01*
X-593539D01*
X-591614Y-86890D01*
G01X-730157Y-101417D02*
X-727977Y-103598D01*
X-727520D01*
X-726736Y-102814D01*
Y-88188D01*
X-709398Y-70850D01*
X-656271D01*
X-634881Y-92240D01*
X-626418D01*
X-622978Y-88800D01*
X-604965D01*
X-603470Y-90295D01*
Y-93415D01*
X-603070Y-93815D01*
X-598539D01*
X-596614Y-91890D01*
G01Y-96890D02*
X-598539Y-94965D01*
X-603546D01*
X-604620Y-93891D01*
Y-90771D01*
X-605441Y-89950D01*
X-622501D01*
X-625941Y-93390D01*
X-635358D01*
X-656748Y-72000D01*
X-708921D01*
X-725586Y-88665D01*
Y-103290D01*
X-727044Y-104748D01*
X-727977D01*
X-730157Y-106929D01*
G01X-714409Y-101417D02*
X-712229Y-103598D01*
X-711291D01*
X-711071Y-103379D01*
Y-93024D01*
X-697098Y-79050D01*
X-665971D01*
X-653348Y-91674D01*
X-647121D01*
X-632505Y-106290D01*
X-624581D01*
X-622061Y-108810D01*
X-604955D01*
X-603480Y-110285D01*
Y-113405D01*
X-603070Y-113815D01*
X-598539D01*
X-596614Y-111890D01*
G01X-722283Y-106535D02*
X-720103Y-108716D01*
X-719277D01*
X-718971Y-108410D01*
Y-90624D01*
X-703298Y-74950D01*
X-657971D01*
X-634111Y-98810D01*
X-599955D01*
X-598490Y-100275D01*
Y-103395D01*
X-598070Y-103815D01*
X-593539D01*
X-591614Y-101890D01*
G01X-596614Y-116890D02*
X-598539Y-114965D01*
X-603546D01*
X-604630Y-113881D01*
Y-110761D01*
X-605431Y-109960D01*
X-622538D01*
X-625058Y-107440D01*
X-632981D01*
X-647598Y-92824D01*
X-653824D01*
X-666448Y-80200D01*
X-696621D01*
X-709921Y-93500D01*
Y-103855D01*
X-710814Y-104748D01*
X-712229D01*
X-714409Y-106929D01*
G01X-591614Y-106890D02*
X-593539Y-104965D01*
X-598546D01*
X-599640Y-103871D01*
Y-100751D01*
X-600431Y-99960D01*
X-634588D01*
X-658448Y-76100D01*
X-702821D01*
X-717821Y-91100D01*
Y-108887D01*
X-718801Y-109866D01*
X-720103D01*
X-722283Y-112047D01*
G01X-706535Y-106535D02*
X-704355Y-108716D01*
X-703614D01*
X-703171Y-108274D01*
Y-93250D01*
X-693071Y-83150D01*
X-667871D01*
X-632191Y-118830D01*
X-599935D01*
X-598480Y-120285D01*
Y-123405D01*
X-598070Y-123815D01*
X-593539D01*
X-591614Y-121890D01*
G01X-698661Y-101417D02*
X-696481Y-103598D01*
X-695892D01*
X-695271Y-102978D01*
Y-93124D01*
X-689498Y-87350D01*
X-669671D01*
X-654421Y-102600D01*
Y-106074D01*
X-634075Y-126420D01*
X-623091D01*
X-620701Y-128810D01*
X-604955D01*
X-603470Y-130295D01*
Y-133415D01*
X-603070Y-133815D01*
X-598539D01*
X-596614Y-131890D01*
G01X-591614Y-126890D02*
X-593539Y-124965D01*
X-598546D01*
X-599630Y-123881D01*
Y-120761D01*
X-600411Y-119980D01*
X-632668D01*
X-668348Y-84300D01*
X-692595D01*
X-702021Y-93726D01*
Y-108750D01*
X-703138Y-109866D01*
X-704355D01*
X-706535Y-112047D01*
G01X-596614Y-136890D02*
X-598539Y-134965D01*
X-603546D01*
X-604620Y-133891D01*
Y-130771D01*
X-605431Y-129960D01*
X-621178D01*
X-623568Y-127570D01*
X-634551D01*
X-655571Y-106550D01*
Y-103076D01*
X-670148Y-88500D01*
X-689021D01*
X-694121Y-93600D01*
Y-103454D01*
X-695415Y-104748D01*
X-696481D01*
X-698661Y-106929D01*
G01X-690787Y-106535D02*
X-688606Y-108716D01*
X-687686D01*
X-687371Y-108401D01*
Y-94050D01*
X-684771Y-91450D01*
X-671771D01*
X-659021Y-104200D01*
Y-115200D01*
X-637611Y-136610D01*
X-625650D01*
X-623460Y-138800D01*
X-599965D01*
X-598480Y-140285D01*
Y-143405D01*
X-598070Y-143815D01*
X-593539D01*
X-591614Y-141890D01*
G01X-682913Y-101417D02*
X-680732Y-103598D01*
X-680232D01*
X-679732Y-103098D01*
Y-98460D01*
X-677722Y-96450D01*
X-672971D01*
X-664171Y-105250D01*
Y-120150D01*
X-637981Y-146340D01*
X-623591D01*
X-621121Y-148810D01*
X-604955D01*
X-603470Y-150295D01*
Y-153415D01*
X-603070Y-153815D01*
X-598539D01*
X-596614Y-151890D01*
G01X-591614Y-146890D02*
X-593539Y-144965D01*
X-598546D01*
X-599630Y-143881D01*
Y-140761D01*
X-600441Y-139950D01*
X-623936D01*
X-626126Y-137760D01*
X-638088D01*
X-660171Y-115676D01*
Y-104676D01*
X-672248Y-92600D01*
X-684295D01*
X-686221Y-94526D01*
Y-108878D01*
X-687210Y-109866D01*
X-688606D01*
X-690787Y-112047D01*
G01X-596614Y-156890D02*
X-598539Y-154965D01*
X-603546D01*
X-604620Y-153891D01*
Y-150771D01*
X-605431Y-149960D01*
X-621598D01*
X-624068Y-147490D01*
X-638458D01*
X-665321Y-120626D01*
Y-105726D01*
X-673448Y-97600D01*
X-677246D01*
X-678582Y-98937D01*
Y-103575D01*
X-679756Y-104748D01*
X-680732D01*
X-682913Y-106929D01*
G01X-591614Y-161890D02*
X-593539Y-163815D01*
X-598206D01*
X-599630Y-165239D01*
Y-168414D01*
X-600466Y-169250D01*
X-623486D01*
X-626466Y-172230D01*
X-658065D01*
X-668471Y-161824D01*
Y-131850D01*
X-669145Y-131176D01*
X-669878Y-130444D01*
Y-110721D01*
X-671882Y-108716D01*
X-672858D01*
X-675039Y-106535D01*
G01X-591614Y-166890D02*
X-593539Y-164965D01*
X-597730D01*
X-598480Y-165715D01*
Y-168890D01*
X-599990Y-170400D01*
X-623010D01*
X-625990Y-173380D01*
X-658541D01*
X-669621Y-162300D01*
Y-132326D01*
X-671028Y-130920D01*
Y-111197D01*
X-672358Y-109866D01*
X-672858D01*
X-675039Y-112047D01*
G54D13*
X-1296260Y-175039D03*
X-1304134D03*
X-1296260Y-167165D03*
X-1304134D03*
X-1296260Y-159291D03*
X-1304134D03*
X-1296260Y-143543D03*
X-1304134D03*
X-1296260Y-135669D03*
X-1304134D03*
X-1296260Y-127795D03*
X-1304134D03*
X-426181Y-175039D03*
X-434055D03*
X-426181Y-167165D03*
X-434055D03*
X-426181Y-159291D03*
X-434055D03*
X-426181Y-143543D03*
X-434055D03*
X-426181Y-135669D03*
X-434055D03*
X-426181Y-127795D03*
X-434055D03*
G54D23*
G01X-874510Y-499000D02*
Y-493000D01*
X-871290Y-499000D01*
Y-493000D01*
G01X-867200Y-499000D02*
X-867760Y-498900D01*
X-868250Y-498500D01*
X-868670Y-497900D01*
X-868950Y-497200D01*
X-869090Y-496400D01*
Y-495600D01*
X-868950Y-494800D01*
X-868670Y-494100D01*
X-868250Y-493500D01*
X-867760Y-493100D01*
X-867200Y-493000D01*
X-866640Y-493100D01*
X-866150Y-493500D01*
X-865730Y-494100D01*
X-865450Y-494800D01*
X-865310Y-495600D01*
Y-496400D01*
X-865450Y-497200D01*
X-865730Y-497900D01*
X-866150Y-498500D01*
X-866640Y-498900D01*
X-867200Y-499000D01*
G01X-861500Y-493000D02*
Y-499000D01*
G01X-863110Y-493000D02*
X-859890D01*
G01X-856640D02*
X-854960D01*
G01X-855800D02*
Y-499000D01*
G01X-856640D02*
X-854960D01*
G01X-848560Y-493500D02*
X-848980Y-493200D01*
X-849470Y-493000D01*
X-850030D01*
X-850660Y-493300D01*
X-851150Y-493800D01*
X-851500Y-494400D01*
X-851780Y-495400D01*
X-851850Y-496300D01*
X-851710Y-497200D01*
X-851500Y-497800D01*
X-851080Y-498400D01*
X-850590Y-498800D01*
X-850100Y-499000D01*
X-849610D01*
X-849120Y-498800D01*
X-848700Y-498500D01*
X-848350Y-498100D01*
G01X-843000Y-499000D02*
X-845800D01*
Y-493000D01*
X-843000D01*
G01X-844120Y-495900D02*
X-845800D01*
G01X-833000Y-499000D02*
X-833560Y-498900D01*
X-834050Y-498500D01*
X-834470Y-497900D01*
X-834750Y-497200D01*
X-834890Y-496400D01*
Y-495600D01*
X-834750Y-494800D01*
X-834470Y-494100D01*
X-834050Y-493500D01*
X-833560Y-493100D01*
X-833000Y-493000D01*
X-832440Y-493100D01*
X-831950Y-493500D01*
X-831530Y-494100D01*
X-831250Y-494800D01*
X-831110Y-495600D01*
Y-496400D01*
X-831250Y-497200D01*
X-831530Y-497900D01*
X-831950Y-498500D01*
X-832440Y-498900D01*
X-833000Y-499000D01*
G01X-828630D02*
Y-493000D01*
X-825970D01*
G01X-826950Y-495900D02*
X-828630D01*
G01X-817300Y-499000D02*
Y-493000D01*
X-815620D01*
X-815060Y-493300D01*
X-814640Y-494000D01*
X-814500Y-494800D01*
X-814640Y-495600D01*
X-814990Y-496200D01*
X-815620Y-496500D01*
X-817300D01*
G01X-811600Y-499000D02*
Y-493000D01*
X-809850D01*
X-809290Y-493300D01*
X-808940Y-493700D01*
X-808800Y-494500D01*
X-808940Y-495300D01*
X-809360Y-495800D01*
X-809850Y-496100D01*
X-811600D01*
G01X-809850D02*
X-808800Y-499000D01*
G01X-804500D02*
X-805060Y-498900D01*
X-805550Y-498500D01*
X-805970Y-497900D01*
X-806250Y-497200D01*
X-806390Y-496400D01*
Y-495600D01*
X-806250Y-494800D01*
X-805970Y-494100D01*
X-805550Y-493500D01*
X-805060Y-493100D01*
X-804500Y-493000D01*
X-803940Y-493100D01*
X-803450Y-493500D01*
X-803030Y-494100D01*
X-802750Y-494800D01*
X-802610Y-495600D01*
Y-496400D01*
X-802750Y-497200D01*
X-803030Y-497900D01*
X-803450Y-498500D01*
X-803940Y-498900D01*
X-804500Y-499000D01*
G01X-800200D02*
Y-493000D01*
X-798520D01*
X-797960Y-493300D01*
X-797540Y-494000D01*
X-797400Y-494800D01*
X-797540Y-495600D01*
X-797890Y-496200D01*
X-798520Y-496500D01*
X-800200D01*
G01X-794500Y-499000D02*
Y-493000D01*
X-792750D01*
X-792190Y-493300D01*
X-791840Y-493700D01*
X-791700Y-494500D01*
X-791840Y-495300D01*
X-792260Y-495800D01*
X-792750Y-496100D01*
X-794500D01*
G01X-792750D02*
X-791700Y-499000D01*
G01X-788240Y-493000D02*
X-786560D01*
G01X-787400D02*
Y-499000D01*
G01X-788240D02*
X-786560D01*
G01X-780300D02*
X-783100D01*
Y-493000D01*
X-780300D01*
G01X-781420Y-495900D02*
X-783100D01*
G01X-776000Y-493000D02*
Y-499000D01*
G01X-777610Y-493000D02*
X-774390D01*
G01X-772050Y-499000D02*
X-770300Y-493000D01*
X-768550Y-499000D01*
G01X-769180Y-496900D02*
X-771420D01*
G01X-766000Y-499000D02*
Y-493000D01*
X-764250D01*
X-763690Y-493300D01*
X-763340Y-493700D01*
X-763200Y-494500D01*
X-763340Y-495300D01*
X-763760Y-495800D01*
X-764250Y-496100D01*
X-766000D01*
G01X-764250D02*
X-763200Y-499000D01*
G01X-758900D02*
Y-496300D01*
X-760300Y-493000D01*
G01X-757500D02*
X-758900Y-496300D01*
G01X-748900Y-499000D02*
Y-493000D01*
X-747220D01*
X-746660Y-493300D01*
X-746240Y-494000D01*
X-746100Y-494800D01*
X-746240Y-495600D01*
X-746590Y-496200D01*
X-747220Y-496500D01*
X-748900D01*
G01X-743200Y-499000D02*
Y-493000D01*
X-741450D01*
X-740890Y-493300D01*
X-740540Y-493700D01*
X-740400Y-494500D01*
X-740540Y-495300D01*
X-740960Y-495800D01*
X-741450Y-496100D01*
X-743200D01*
G01X-741450D02*
X-740400Y-499000D01*
G01X-736100D02*
X-736660Y-498900D01*
X-737150Y-498500D01*
X-737570Y-497900D01*
X-737850Y-497200D01*
X-737990Y-496400D01*
Y-495600D01*
X-737850Y-494800D01*
X-737570Y-494100D01*
X-737150Y-493500D01*
X-736660Y-493100D01*
X-736100Y-493000D01*
X-735540Y-493100D01*
X-735050Y-493500D01*
X-734630Y-494100D01*
X-734350Y-494800D01*
X-734210Y-495600D01*
Y-496400D01*
X-734350Y-497200D01*
X-734630Y-497900D01*
X-735050Y-498500D01*
X-735540Y-498900D01*
X-736100Y-499000D01*
G01X-731800D02*
Y-493000D01*
X-730120D01*
X-729560Y-493300D01*
X-729140Y-494000D01*
X-729000Y-494800D01*
X-729140Y-495600D01*
X-729490Y-496200D01*
X-730120Y-496500D01*
X-731800D01*
G01X-723300Y-499000D02*
X-726100D01*
Y-493000D01*
X-723300D01*
G01X-724420Y-495900D02*
X-726100D01*
G01X-720400Y-499000D02*
Y-493000D01*
X-718650D01*
X-718090Y-493300D01*
X-717740Y-493700D01*
X-717600Y-494500D01*
X-717740Y-495300D01*
X-718160Y-495800D01*
X-718650Y-496100D01*
X-720400D01*
G01X-718650D02*
X-717600Y-499000D01*
G01X-713300Y-493000D02*
Y-499000D01*
G01X-714910Y-493000D02*
X-711690D01*
G01X-707600Y-499000D02*
Y-496300D01*
X-709000Y-493000D01*
G01X-706200D02*
X-707600Y-496300D01*
G01X-701900Y-499200D02*
X-702040Y-499100D01*
Y-498900D01*
X-701900Y-498800D01*
X-701760Y-498900D01*
Y-499100D01*
X-701900Y-499200D01*
G01Y-496500D02*
X-702040Y-496400D01*
Y-496200D01*
X-701900Y-496100D01*
X-701760Y-496200D01*
Y-496400D01*
X-701900Y-496500D01*
G54D14*
X-1012205Y-93068D03*
X-1009252Y-98580D03*
X-1012205Y-78108D03*
X-1009252Y-83620D03*
X-1012205Y-63147D03*
X-1009252Y-68659D03*
X-1012205Y-48187D03*
X-1009252Y-53698D03*
X-1000394Y-98580D03*
X-1003346Y-93068D03*
X-968898D03*
X-965945Y-98580D03*
Y-83620D03*
X-968898Y-78108D03*
X-965945Y-68659D03*
X-968898Y-63147D03*
X-960039Y-93068D03*
X-957087Y-98580D03*
X-142126Y-93068D03*
X-139173Y-98580D03*
X-130315D03*
X-133268Y-93068D03*
X-142126Y-78108D03*
X-139173Y-83620D03*
X-142126Y-63147D03*
X-139173Y-68659D03*
X-142126Y-48187D03*
X-139173Y-53698D03*
X-98819Y-93068D03*
X-95866Y-98580D03*
Y-83620D03*
X-98819Y-78108D03*
X-95866Y-68659D03*
X-98819Y-63147D03*
X-89961Y-93068D03*
X-87008Y-98580D03*
G54D24*
G01X-1247979Y-177933D02*
X-1248930Y-176982D01*
Y-169230D01*
X-1250500Y-167660D01*
X-1273250D01*
X-1276860Y-171270D01*
Y-178030D01*
G01X-316500Y-113500D02*
X-318000D01*
X-325800Y-105700D01*
X-346630D01*
X-373320Y-132390D01*
X-392740D01*
X-402830Y-142480D01*
Y-144060D01*
X-409580Y-150810D01*
Y-166500D01*
X-407620Y-168460D01*
Y-174280D01*
X-414540Y-181200D01*
X-579800D01*
X-586330Y-174670D01*
X-621620D01*
X-629550Y-182600D01*
X-724350D01*
X-726200Y-180750D01*
Y-143957D01*
X-730157Y-140000D01*
G01X-321600Y-113500D02*
X-326200D01*
X-332100Y-107600D01*
X-345960D01*
X-372900Y-134540D01*
X-391030D01*
X-407700Y-151210D01*
Y-164830D01*
X-406160Y-166370D01*
Y-174730D01*
X-414730Y-183300D01*
X-581500D01*
X-585100Y-179700D01*
X-591200D01*
G01X-367913Y-179850D02*
Y-177837D01*
X-369390Y-176360D01*
Y-169420D01*
X-371720Y-167090D01*
X-403570D01*
X-404920Y-168440D01*
Y-175760D01*
X-407970Y-178810D01*
Y-180600D01*
X-405540Y-183030D01*
Y-183080D01*
G01Y-179630D02*
Y-178160D01*
X-403800Y-176420D01*
Y-169080D01*
X-402990Y-168270D01*
X-379790D01*
X-378930Y-169130D01*
Y-176903D01*
X-377900Y-177933D01*
G01X-303200Y-43300D02*
X-302000D01*
X-277600Y-67700D01*
Y-72700D01*
X-261700Y-88600D01*
Y-116420D01*
X-276780Y-131500D01*
Y-145750D01*
X-274400Y-148130D01*
Y-178200D01*
G01X-303200Y-48800D02*
X-299650D01*
X-280425Y-68025D01*
Y-72275D01*
X-264200Y-88500D01*
Y-116540D01*
X-278100Y-130440D01*
Y-146760D01*
X-275870Y-148990D01*
Y-172816D01*
G02X-278100Y-178200I-7614J0D01*
G54D15*
X-806854Y-83100D03*
X-785200D03*
G54D25*
G01X-1189333Y-572500D02*
Y-565500D01*
X-1187667D01*
X-1187000Y-565850D01*
X-1186500Y-566317D01*
X-1186083Y-567017D01*
X-1185750Y-567833D01*
X-1185667Y-569000D01*
X-1185750Y-570167D01*
X-1186083Y-570983D01*
X-1186500Y-571684D01*
X-1187000Y-572150D01*
X-1187667Y-572500D01*
X-1189333D01*
G01X-1180700D02*
X-1181367Y-572383D01*
X-1181950Y-571917D01*
X-1182450Y-571217D01*
X-1182783Y-570400D01*
X-1182950Y-569467D01*
Y-568533D01*
X-1182783Y-567600D01*
X-1182450Y-566783D01*
X-1181950Y-566083D01*
X-1181367Y-565617D01*
X-1180700Y-565500D01*
X-1180033Y-565617D01*
X-1179450Y-566083D01*
X-1178950Y-566783D01*
X-1178617Y-567600D01*
X-1178450Y-568533D01*
Y-569467D01*
X-1178617Y-570400D01*
X-1178950Y-571217D01*
X-1179450Y-571917D01*
X-1180033Y-572383D01*
X-1180700Y-572500D01*
G01X-1172067Y-566083D02*
X-1172567Y-565733D01*
X-1173150Y-565500D01*
X-1173817D01*
X-1174567Y-565850D01*
X-1175150Y-566433D01*
X-1175567Y-567133D01*
X-1175900Y-568300D01*
X-1175983Y-569350D01*
X-1175817Y-570400D01*
X-1175567Y-571100D01*
X-1175067Y-571800D01*
X-1174483Y-572267D01*
X-1173900Y-572500D01*
X-1173317D01*
X-1172733Y-572267D01*
X-1172233Y-571917D01*
X-1171817Y-571450D01*
G01X-1168933Y-565500D02*
Y-570517D01*
X-1168600Y-571567D01*
X-1167933Y-572267D01*
X-1167100Y-572500D01*
X-1166267Y-572267D01*
X-1165600Y-571567D01*
X-1165267Y-570517D01*
Y-565500D01*
G01X-1162467Y-572500D02*
Y-565500D01*
X-1160300Y-571333D01*
X-1158133Y-565500D01*
Y-572500D01*
G01X-1151833D02*
X-1155167D01*
Y-565500D01*
X-1151833D01*
G01X-1153167Y-568883D02*
X-1155167D01*
G01X-1148617Y-572500D02*
Y-565500D01*
X-1144783Y-572500D01*
Y-565500D01*
G01X-1139900D02*
Y-572500D01*
G01X-1141817Y-565500D02*
X-1137983D01*
G01X-1128217Y-572500D02*
Y-565500D01*
X-1124383Y-572500D01*
Y-565500D01*
G01X-1121333D02*
Y-570517D01*
X-1121000Y-571567D01*
X-1120333Y-572267D01*
X-1119500Y-572500D01*
X-1118667Y-572267D01*
X-1118000Y-571567D01*
X-1117667Y-570517D01*
Y-565500D01*
G01X-1114867Y-572500D02*
Y-565500D01*
X-1112700Y-571333D01*
X-1110533Y-565500D01*
Y-572500D01*
G01X-1105233Y-568767D02*
X-1104900Y-568417D01*
X-1104650Y-567833D01*
X-1104483Y-567017D01*
X-1104650Y-566317D01*
X-1104983Y-565850D01*
X-1105567Y-565500D01*
X-1107817D01*
Y-572500D01*
X-1105067D01*
X-1104483Y-572033D01*
X-1104150Y-571333D01*
X-1103983Y-570517D01*
X-1104150Y-569700D01*
X-1104650Y-569000D01*
X-1105233Y-568767D01*
X-1107817D01*
G01X-1097433Y-572500D02*
X-1100767D01*
Y-565500D01*
X-1097433D01*
G01X-1098767Y-568883D02*
X-1100767D01*
G01X-1093967Y-572500D02*
Y-565500D01*
X-1091883D01*
X-1091217Y-565850D01*
X-1090800Y-566317D01*
X-1090633Y-567250D01*
X-1090800Y-568183D01*
X-1091300Y-568767D01*
X-1091883Y-569117D01*
X-1093967D01*
G01X-1091883D02*
X-1090633Y-572500D01*
G01X-1189250Y-531567D02*
X-1188583Y-532150D01*
X-1187833Y-532500D01*
X-1187167D01*
X-1186500Y-532150D01*
X-1186000Y-531567D01*
X-1185750Y-530750D01*
X-1185917Y-529933D01*
X-1186333Y-529233D01*
X-1187083Y-528767D01*
X-1188083Y-528533D01*
X-1188667Y-528067D01*
X-1188917Y-527250D01*
X-1188750Y-526433D01*
X-1188333Y-525850D01*
X-1187750Y-525500D01*
X-1187167D01*
X-1186583Y-525733D01*
X-1186083Y-526317D01*
G01X-1182450Y-532500D02*
Y-525500D01*
G01X-1178950D02*
Y-532500D01*
G01Y-529000D02*
X-1182450D01*
G01X-1172233Y-532500D02*
X-1175567D01*
Y-525500D01*
X-1172233D01*
G01X-1173567Y-528883D02*
X-1175567D01*
G01X-1165433Y-532500D02*
X-1168767D01*
Y-525500D01*
X-1165433D01*
G01X-1166767Y-528883D02*
X-1168767D01*
G01X-1160300Y-525500D02*
Y-532500D01*
G01X-1162217Y-525500D02*
X-1158383D01*
G01X-1146700D02*
Y-532500D01*
G01X-1148617Y-525500D02*
X-1144783D01*
G01X-1140900D02*
X-1138900D01*
G01X-1139900D02*
Y-532500D01*
G01X-1140900D02*
X-1138900D01*
G01X-1133100Y-525500D02*
Y-532500D01*
G01X-1135017Y-525500D02*
X-1131183D01*
G01X-1127967D02*
Y-532500D01*
X-1124633D01*
G01X-1117833D02*
X-1121167D01*
Y-525500D01*
X-1117833D01*
G01X-1119167Y-528883D02*
X-1121167D01*
G01X-1112700Y-532733D02*
X-1112867Y-532617D01*
Y-532383D01*
X-1112700Y-532267D01*
X-1112533Y-532383D01*
Y-532617D01*
X-1112700Y-532733D01*
G01Y-529584D02*
X-1112867Y-529467D01*
Y-529233D01*
X-1112700Y-529117D01*
X-1112533Y-529233D01*
Y-529467D01*
X-1112700Y-529584D01*
G01X-1187500Y-485500D02*
Y-492500D01*
G01X-1189417Y-485500D02*
X-1185583D01*
G01X-1181700D02*
X-1179700D01*
G01X-1180700D02*
Y-492500D01*
G01X-1181700D02*
X-1179700D01*
G01X-1173900Y-485500D02*
Y-492500D01*
G01X-1175817Y-485500D02*
X-1171983D01*
G01X-1168767D02*
Y-492500D01*
X-1165433D01*
G01X-1158633D02*
X-1161967D01*
Y-485500D01*
X-1158633D01*
G01X-1159967Y-488883D02*
X-1161967D01*
G01X-916667Y-570000D02*
Y-563000D01*
X-914583D01*
X-913917Y-563350D01*
X-913500Y-563817D01*
X-913333Y-564750D01*
X-913500Y-565683D01*
X-914000Y-566267D01*
X-914583Y-566617D01*
X-916667D01*
G01X-914583D02*
X-913333Y-570000D01*
G01X-906533D02*
X-909867D01*
Y-563000D01*
X-906533D01*
G01X-907867Y-566383D02*
X-909867D01*
G01X-903483Y-563000D02*
X-901400Y-570000D01*
X-899317Y-563000D01*
G01X-907850Y-451567D02*
X-907183Y-452150D01*
X-906433Y-452500D01*
X-905767D01*
X-905100Y-452150D01*
X-904600Y-451567D01*
X-904350Y-450750D01*
X-904517Y-449933D01*
X-904933Y-449233D01*
X-905683Y-448767D01*
X-906683Y-448533D01*
X-907267Y-448067D01*
X-907517Y-447250D01*
X-907350Y-446433D01*
X-906933Y-445850D01*
X-906350Y-445500D01*
X-905767D01*
X-905183Y-445733D01*
X-904683Y-446317D01*
G01X-897467Y-446083D02*
X-897967Y-445733D01*
X-898550Y-445500D01*
X-899217D01*
X-899967Y-445850D01*
X-900550Y-446433D01*
X-900967Y-447133D01*
X-901300Y-448300D01*
X-901383Y-449350D01*
X-901217Y-450400D01*
X-900967Y-451100D01*
X-900467Y-451800D01*
X-899883Y-452267D01*
X-899300Y-452500D01*
X-898717D01*
X-898133Y-452267D01*
X-897633Y-451917D01*
X-897217Y-451450D01*
G01X-894583Y-452500D02*
X-892500Y-445500D01*
X-890417Y-452500D01*
G01X-891167Y-450050D02*
X-893833D01*
G01X-887367Y-445500D02*
Y-452500D01*
X-884033D01*
G01X-877233D02*
X-880567D01*
Y-445500D01*
X-877233D01*
G01X-878567Y-448883D02*
X-880567D01*
G01X-874333Y-572500D02*
Y-565500D01*
X-872667D01*
X-872000Y-565850D01*
X-871500Y-566317D01*
X-871083Y-567017D01*
X-870750Y-567833D01*
X-870667Y-569000D01*
X-870750Y-570167D01*
X-871083Y-570983D01*
X-871500Y-571684D01*
X-872000Y-572150D01*
X-872667Y-572500D01*
X-874333D01*
G01X-866700Y-565500D02*
X-864700D01*
G01X-865700D02*
Y-572500D01*
G01X-866700D02*
X-864700D01*
G01X-860650Y-571567D02*
X-859983Y-572150D01*
X-859233Y-572500D01*
X-858567D01*
X-857900Y-572150D01*
X-857400Y-571567D01*
X-857150Y-570750D01*
X-857317Y-569933D01*
X-857733Y-569233D01*
X-858483Y-568767D01*
X-859483Y-568533D01*
X-860067Y-568067D01*
X-860317Y-567250D01*
X-860150Y-566433D01*
X-859733Y-565850D01*
X-859150Y-565500D01*
X-858567D01*
X-857983Y-565733D01*
X-857483Y-566317D01*
G01X-850267Y-566083D02*
X-850767Y-565733D01*
X-851350Y-565500D01*
X-852017D01*
X-852767Y-565850D01*
X-853350Y-566433D01*
X-853767Y-567133D01*
X-854100Y-568300D01*
X-854183Y-569350D01*
X-854017Y-570400D01*
X-853767Y-571100D01*
X-853267Y-571800D01*
X-852683Y-572267D01*
X-852100Y-572500D01*
X-851517D01*
X-850933Y-572267D01*
X-850433Y-571917D01*
X-850017Y-571450D01*
G01X-846967Y-565500D02*
Y-572500D01*
X-843633D01*
G01X-838500D02*
X-839167Y-572383D01*
X-839750Y-571917D01*
X-840250Y-571217D01*
X-840583Y-570400D01*
X-840750Y-569467D01*
Y-568533D01*
X-840583Y-567600D01*
X-840250Y-566783D01*
X-839750Y-566083D01*
X-839167Y-565617D01*
X-838500Y-565500D01*
X-837833Y-565617D01*
X-837250Y-566083D01*
X-836750Y-566783D01*
X-836417Y-567600D01*
X-836250Y-568533D01*
Y-569467D01*
X-836417Y-570400D01*
X-836750Y-571217D01*
X-837250Y-571917D01*
X-837833Y-572383D01*
X-838500Y-572500D01*
G01X-833450Y-571567D02*
X-832783Y-572150D01*
X-832033Y-572500D01*
X-831367D01*
X-830700Y-572150D01*
X-830200Y-571567D01*
X-829950Y-570750D01*
X-830117Y-569933D01*
X-830533Y-569233D01*
X-831283Y-568767D01*
X-832283Y-568533D01*
X-832867Y-568067D01*
X-833117Y-567250D01*
X-832950Y-566433D01*
X-832533Y-565850D01*
X-831950Y-565500D01*
X-831367D01*
X-830783Y-565733D01*
X-830283Y-566317D01*
G01X-823233Y-572500D02*
X-826567D01*
Y-565500D01*
X-823233D01*
G01X-824567Y-568883D02*
X-826567D01*
G01X-819933Y-572500D02*
Y-565500D01*
X-818267D01*
X-817600Y-565850D01*
X-817100Y-566317D01*
X-816683Y-567017D01*
X-816350Y-567833D01*
X-816267Y-569000D01*
X-816350Y-570167D01*
X-816683Y-570983D01*
X-817100Y-571684D01*
X-817600Y-572150D01*
X-818267Y-572500D01*
X-819933D01*
G01X-807000Y-565500D02*
X-805833Y-572500D01*
X-804500Y-565500D01*
X-803167Y-572500D01*
X-802000Y-565500D01*
G01X-798700D02*
X-796700D01*
G01X-797700D02*
Y-572500D01*
G01X-798700D02*
X-796700D01*
G01X-790900Y-565500D02*
Y-572500D01*
G01X-792817Y-565500D02*
X-788983D01*
G01X-785850Y-572500D02*
Y-565500D01*
G01X-782350D02*
Y-572500D01*
G01Y-569000D02*
X-785850D01*
G01X-777300Y-572500D02*
X-777967Y-572383D01*
X-778550Y-571917D01*
X-779050Y-571217D01*
X-779383Y-570400D01*
X-779550Y-569467D01*
Y-568533D01*
X-779383Y-567600D01*
X-779050Y-566783D01*
X-778550Y-566083D01*
X-777967Y-565617D01*
X-777300Y-565500D01*
X-776633Y-565617D01*
X-776050Y-566083D01*
X-775550Y-566783D01*
X-775217Y-567600D01*
X-775050Y-568533D01*
Y-569467D01*
X-775217Y-570400D01*
X-775550Y-571217D01*
X-776050Y-571917D01*
X-776633Y-572383D01*
X-777300Y-572500D01*
G01X-772333Y-565500D02*
Y-570517D01*
X-772000Y-571567D01*
X-771333Y-572267D01*
X-770500Y-572500D01*
X-769667Y-572267D01*
X-769000Y-571567D01*
X-768667Y-570517D01*
Y-565500D01*
G01X-763700D02*
Y-572500D01*
G01X-765617Y-565500D02*
X-761783D01*
G01X-750100D02*
Y-572500D01*
G01X-752017Y-565500D02*
X-748183D01*
G01X-745050Y-572500D02*
Y-565500D01*
G01X-741550D02*
Y-572500D01*
G01Y-569000D02*
X-745050D01*
G01X-734833Y-572500D02*
X-738167D01*
Y-565500D01*
X-734833D01*
G01X-736167Y-568883D02*
X-738167D01*
G01X-724567Y-572500D02*
Y-565500D01*
X-722567D01*
X-721900Y-565850D01*
X-721400Y-566667D01*
X-721233Y-567600D01*
X-721400Y-568533D01*
X-721817Y-569233D01*
X-722567Y-569584D01*
X-724567D01*
G01X-717767Y-572500D02*
Y-565500D01*
X-715683D01*
X-715017Y-565850D01*
X-714600Y-566317D01*
X-714433Y-567250D01*
X-714600Y-568183D01*
X-715100Y-568767D01*
X-715683Y-569117D01*
X-717767D01*
G01X-715683D02*
X-714433Y-572500D01*
G01X-710300Y-565500D02*
X-708300D01*
G01X-709300D02*
Y-572500D01*
G01X-710300D02*
X-708300D01*
G01X-702500D02*
X-703167Y-572383D01*
X-703750Y-571917D01*
X-704250Y-571217D01*
X-704583Y-570400D01*
X-704750Y-569467D01*
Y-568533D01*
X-704583Y-567600D01*
X-704250Y-566783D01*
X-703750Y-566083D01*
X-703167Y-565617D01*
X-702500Y-565500D01*
X-701833Y-565617D01*
X-701250Y-566083D01*
X-700750Y-566783D01*
X-700417Y-567600D01*
X-700250Y-568533D01*
Y-569467D01*
X-700417Y-570400D01*
X-700750Y-571217D01*
X-701250Y-571917D01*
X-701833Y-572383D01*
X-702500Y-572500D01*
G01X-697367D02*
Y-565500D01*
X-695283D01*
X-694617Y-565850D01*
X-694200Y-566317D01*
X-694033Y-567250D01*
X-694200Y-568183D01*
X-694700Y-568767D01*
X-695283Y-569117D01*
X-697367D01*
G01X-695283D02*
X-694033Y-572500D01*
G01X-684600Y-565500D02*
X-683433Y-572500D01*
X-682100Y-565500D01*
X-680767Y-572500D01*
X-679600Y-565500D01*
G01X-676967Y-572500D02*
Y-565500D01*
X-674883D01*
X-674217Y-565850D01*
X-673800Y-566317D01*
X-673633Y-567250D01*
X-673800Y-568183D01*
X-674300Y-568767D01*
X-674883Y-569117D01*
X-676967D01*
G01X-674883D02*
X-673633Y-572500D01*
G01X-669500Y-565500D02*
X-667500D01*
G01X-668500D02*
Y-572500D01*
G01X-669500D02*
X-667500D01*
G01X-661700Y-565500D02*
Y-572500D01*
G01X-663617Y-565500D02*
X-659783D01*
G01X-654900D02*
Y-572500D01*
G01X-656817Y-565500D02*
X-652983D01*
G01X-646433Y-572500D02*
X-649767D01*
Y-565500D01*
X-646433D01*
G01X-647767Y-568883D02*
X-649767D01*
G01X-643217Y-572500D02*
Y-565500D01*
X-639383Y-572500D01*
Y-565500D01*
G01X-625867Y-566083D02*
X-626367Y-565733D01*
X-626950Y-565500D01*
X-627617D01*
X-628367Y-565850D01*
X-628950Y-566433D01*
X-629367Y-567133D01*
X-629700Y-568300D01*
X-629783Y-569350D01*
X-629617Y-570400D01*
X-629367Y-571100D01*
X-628867Y-571800D01*
X-628283Y-572267D01*
X-627700Y-572500D01*
X-627117D01*
X-626533Y-572267D01*
X-626033Y-571917D01*
X-625617Y-571450D01*
G01X-620900Y-572500D02*
X-621567Y-572383D01*
X-622150Y-571917D01*
X-622650Y-571217D01*
X-622983Y-570400D01*
X-623150Y-569467D01*
Y-568533D01*
X-622983Y-567600D01*
X-622650Y-566783D01*
X-622150Y-566083D01*
X-621567Y-565617D01*
X-620900Y-565500D01*
X-620233Y-565617D01*
X-619650Y-566083D01*
X-619150Y-566783D01*
X-618817Y-567600D01*
X-618650Y-568533D01*
Y-569467D01*
X-618817Y-570400D01*
X-619150Y-571217D01*
X-619650Y-571917D01*
X-620233Y-572383D01*
X-620900Y-572500D01*
G01X-616017D02*
Y-565500D01*
X-612183Y-572500D01*
Y-565500D01*
G01X-609050Y-571567D02*
X-608383Y-572150D01*
X-607633Y-572500D01*
X-606967D01*
X-606300Y-572150D01*
X-605800Y-571567D01*
X-605550Y-570750D01*
X-605717Y-569933D01*
X-606133Y-569233D01*
X-606883Y-568767D01*
X-607883Y-568533D01*
X-608467Y-568067D01*
X-608717Y-567250D01*
X-608550Y-566433D01*
X-608133Y-565850D01*
X-607550Y-565500D01*
X-606967D01*
X-606383Y-565733D01*
X-605883Y-566317D01*
G01X-598833Y-572500D02*
X-602167D01*
Y-565500D01*
X-598833D01*
G01X-600167Y-568883D02*
X-602167D01*
G01X-595617Y-572500D02*
Y-565500D01*
X-591783Y-572500D01*
Y-565500D01*
G01X-586900D02*
Y-572500D01*
G01X-588817Y-565500D02*
X-584983D01*
G01X-872500Y-587500D02*
X-873167Y-587383D01*
X-873750Y-586917D01*
X-874250Y-586217D01*
X-874583Y-585400D01*
X-874750Y-584467D01*
Y-583533D01*
X-874583Y-582600D01*
X-874250Y-581783D01*
X-873750Y-581083D01*
X-873167Y-580617D01*
X-872500Y-580500D01*
X-871833Y-580617D01*
X-871250Y-581083D01*
X-870750Y-581783D01*
X-870417Y-582600D01*
X-870250Y-583533D01*
Y-584467D01*
X-870417Y-585400D01*
X-870750Y-586217D01*
X-871250Y-586917D01*
X-871833Y-587383D01*
X-872500Y-587500D01*
G01X-867283D02*
Y-580500D01*
X-864117D01*
G01X-865283Y-583883D02*
X-867283D01*
G01X-854267Y-587500D02*
Y-580500D01*
X-852100Y-586333D01*
X-849933Y-580500D01*
Y-587500D01*
G01X-846300Y-580500D02*
X-844300D01*
G01X-845300D02*
Y-587500D01*
G01X-846300D02*
X-844300D01*
G01X-836667Y-581083D02*
X-837167Y-580733D01*
X-837750Y-580500D01*
X-838417D01*
X-839167Y-580850D01*
X-839750Y-581433D01*
X-840167Y-582133D01*
X-840500Y-583300D01*
X-840583Y-584350D01*
X-840417Y-585400D01*
X-840167Y-586100D01*
X-839667Y-586800D01*
X-839083Y-587267D01*
X-838500Y-587500D01*
X-837917D01*
X-837333Y-587267D01*
X-836833Y-586917D01*
X-836417Y-586450D01*
G01X-833367Y-587500D02*
Y-580500D01*
X-831283D01*
X-830617Y-580850D01*
X-830200Y-581317D01*
X-830033Y-582250D01*
X-830200Y-583183D01*
X-830700Y-583767D01*
X-831283Y-584117D01*
X-833367D01*
G01X-831283D02*
X-830033Y-587500D01*
G01X-824900D02*
X-825567Y-587383D01*
X-826150Y-586917D01*
X-826650Y-586217D01*
X-826983Y-585400D01*
X-827150Y-584467D01*
Y-583533D01*
X-826983Y-582600D01*
X-826650Y-581783D01*
X-826150Y-581083D01*
X-825567Y-580617D01*
X-824900Y-580500D01*
X-824233Y-580617D01*
X-823650Y-581083D01*
X-823150Y-581783D01*
X-822817Y-582600D01*
X-822650Y-583533D01*
Y-584467D01*
X-822817Y-585400D01*
X-823150Y-586217D01*
X-823650Y-586917D01*
X-824233Y-587383D01*
X-824900Y-587500D01*
G01X-819850Y-586567D02*
X-819183Y-587150D01*
X-818433Y-587500D01*
X-817767D01*
X-817100Y-587150D01*
X-816600Y-586567D01*
X-816350Y-585750D01*
X-816517Y-584933D01*
X-816933Y-584233D01*
X-817683Y-583767D01*
X-818683Y-583533D01*
X-819267Y-583067D01*
X-819517Y-582250D01*
X-819350Y-581433D01*
X-818933Y-580850D01*
X-818350Y-580500D01*
X-817767D01*
X-817183Y-580733D01*
X-816683Y-581317D01*
G01X-811300Y-587500D02*
X-811967Y-587383D01*
X-812550Y-586917D01*
X-813050Y-586217D01*
X-813383Y-585400D01*
X-813550Y-584467D01*
Y-583533D01*
X-813383Y-582600D01*
X-813050Y-581783D01*
X-812550Y-581083D01*
X-811967Y-580617D01*
X-811300Y-580500D01*
X-810633Y-580617D01*
X-810050Y-581083D01*
X-809550Y-581783D01*
X-809217Y-582600D01*
X-809050Y-583533D01*
Y-584467D01*
X-809217Y-585400D01*
X-809550Y-586217D01*
X-810050Y-586917D01*
X-810633Y-587383D01*
X-811300Y-587500D01*
G01X-806083D02*
Y-580500D01*
X-802917D01*
G01X-804083Y-583883D02*
X-806083D01*
G01X-797700Y-580500D02*
Y-587500D01*
G01X-799617Y-580500D02*
X-795783D01*
G01X-782267Y-581083D02*
X-782767Y-580733D01*
X-783350Y-580500D01*
X-784017D01*
X-784767Y-580850D01*
X-785350Y-581433D01*
X-785767Y-582133D01*
X-786100Y-583300D01*
X-786183Y-584350D01*
X-786017Y-585400D01*
X-785767Y-586100D01*
X-785267Y-586800D01*
X-784683Y-587267D01*
X-784100Y-587500D01*
X-783517D01*
X-782933Y-587267D01*
X-782433Y-586917D01*
X-782017Y-586450D01*
G01X-777300Y-587500D02*
X-777967Y-587383D01*
X-778550Y-586917D01*
X-779050Y-586217D01*
X-779383Y-585400D01*
X-779550Y-584467D01*
Y-583533D01*
X-779383Y-582600D01*
X-779050Y-581783D01*
X-778550Y-581083D01*
X-777967Y-580617D01*
X-777300Y-580500D01*
X-776633Y-580617D01*
X-776050Y-581083D01*
X-775550Y-581783D01*
X-775217Y-582600D01*
X-775050Y-583533D01*
Y-584467D01*
X-775217Y-585400D01*
X-775550Y-586217D01*
X-776050Y-586917D01*
X-776633Y-587383D01*
X-777300Y-587500D01*
G01X-772167D02*
Y-580500D01*
X-770083D01*
X-769417Y-580850D01*
X-769000Y-581317D01*
X-768833Y-582250D01*
X-769000Y-583183D01*
X-769500Y-583767D01*
X-770083Y-584117D01*
X-772167D01*
G01X-770083D02*
X-768833Y-587500D01*
G01X-765367D02*
Y-580500D01*
X-763367D01*
X-762700Y-580850D01*
X-762200Y-581667D01*
X-762033Y-582600D01*
X-762200Y-583533D01*
X-762617Y-584233D01*
X-763367Y-584584D01*
X-765367D01*
G01X-756900Y-587500D02*
X-757567Y-587383D01*
X-758150Y-586917D01*
X-758650Y-586217D01*
X-758983Y-585400D01*
X-759150Y-584467D01*
Y-583533D01*
X-758983Y-582600D01*
X-758650Y-581783D01*
X-758150Y-581083D01*
X-757567Y-580617D01*
X-756900Y-580500D01*
X-756233Y-580617D01*
X-755650Y-581083D01*
X-755150Y-581783D01*
X-754817Y-582600D01*
X-754650Y-583533D01*
Y-584467D01*
X-754817Y-585400D01*
X-755150Y-586217D01*
X-755650Y-586917D01*
X-756233Y-587383D01*
X-756900Y-587500D01*
G01X-751767D02*
Y-580500D01*
X-749683D01*
X-749017Y-580850D01*
X-748600Y-581317D01*
X-748433Y-582250D01*
X-748600Y-583183D01*
X-749100Y-583767D01*
X-749683Y-584117D01*
X-751767D01*
G01X-749683D02*
X-748433Y-587500D01*
G01X-745383D02*
X-743300Y-580500D01*
X-741217Y-587500D01*
G01X-741967Y-585050D02*
X-744633D01*
G01X-736500Y-580500D02*
Y-587500D01*
G01X-738417Y-580500D02*
X-734583D01*
G01X-730700D02*
X-728700D01*
G01X-729700D02*
Y-587500D01*
G01X-730700D02*
X-728700D01*
G01X-722900D02*
X-723567Y-587383D01*
X-724150Y-586917D01*
X-724650Y-586217D01*
X-724983Y-585400D01*
X-725150Y-584467D01*
Y-583533D01*
X-724983Y-582600D01*
X-724650Y-581783D01*
X-724150Y-581083D01*
X-723567Y-580617D01*
X-722900Y-580500D01*
X-722233Y-580617D01*
X-721650Y-581083D01*
X-721150Y-581783D01*
X-720817Y-582600D01*
X-720650Y-583533D01*
Y-584467D01*
X-720817Y-585400D01*
X-721150Y-586217D01*
X-721650Y-586917D01*
X-722233Y-587383D01*
X-722900Y-587500D01*
G01X-718017D02*
Y-580500D01*
X-714183Y-587500D01*
Y-580500D01*
G01X-709300Y-587733D02*
X-709467Y-587617D01*
Y-587383D01*
X-709300Y-587267D01*
X-709133Y-587383D01*
Y-587617D01*
X-709300Y-587733D01*
G01X-870667Y-551083D02*
X-871167Y-550733D01*
X-871750Y-550500D01*
X-872417D01*
X-873167Y-550850D01*
X-873750Y-551433D01*
X-874167Y-552133D01*
X-874500Y-553300D01*
X-874583Y-554350D01*
X-874417Y-555400D01*
X-874167Y-556100D01*
X-873667Y-556800D01*
X-873083Y-557267D01*
X-872500Y-557500D01*
X-871917D01*
X-871333Y-557267D01*
X-870833Y-556917D01*
X-870417Y-556450D01*
G01X-865700Y-557500D02*
X-866367Y-557383D01*
X-866950Y-556917D01*
X-867450Y-556217D01*
X-867783Y-555400D01*
X-867950Y-554467D01*
Y-553533D01*
X-867783Y-552600D01*
X-867450Y-551783D01*
X-866950Y-551083D01*
X-866367Y-550617D01*
X-865700Y-550500D01*
X-865033Y-550617D01*
X-864450Y-551083D01*
X-863950Y-551783D01*
X-863617Y-552600D01*
X-863450Y-553533D01*
Y-554467D01*
X-863617Y-555400D01*
X-863950Y-556217D01*
X-864450Y-556917D01*
X-865033Y-557383D01*
X-865700Y-557500D01*
G01X-860817D02*
Y-550500D01*
X-856983Y-557500D01*
Y-550500D01*
G01X-853683Y-557500D02*
Y-550500D01*
X-850517D01*
G01X-851683Y-553883D02*
X-853683D01*
G01X-846300Y-550500D02*
X-844300D01*
G01X-845300D02*
Y-557500D01*
G01X-846300D02*
X-844300D01*
G01X-840333D02*
Y-550500D01*
X-838667D01*
X-838000Y-550850D01*
X-837500Y-551317D01*
X-837083Y-552017D01*
X-836750Y-552833D01*
X-836667Y-554000D01*
X-836750Y-555167D01*
X-837083Y-555983D01*
X-837500Y-556684D01*
X-838000Y-557150D01*
X-838667Y-557500D01*
X-840333D01*
G01X-830033D02*
X-833367D01*
Y-550500D01*
X-830033D01*
G01X-831367Y-553883D02*
X-833367D01*
G01X-826817Y-557500D02*
Y-550500D01*
X-822983Y-557500D01*
Y-550500D01*
G01X-816267Y-551083D02*
X-816767Y-550733D01*
X-817350Y-550500D01*
X-818017D01*
X-818767Y-550850D01*
X-819350Y-551433D01*
X-819767Y-552133D01*
X-820100Y-553300D01*
X-820183Y-554350D01*
X-820017Y-555400D01*
X-819767Y-556100D01*
X-819267Y-556800D01*
X-818683Y-557267D01*
X-818100Y-557500D01*
X-817517D01*
X-816933Y-557267D01*
X-816433Y-556917D01*
X-816017Y-556450D01*
G01X-809633Y-557500D02*
X-812967D01*
Y-550500D01*
X-809633D01*
G01X-810967Y-553883D02*
X-812967D01*
G01X-799783Y-557500D02*
X-797700Y-550500D01*
X-795617Y-557500D01*
G01X-796367Y-555050D02*
X-799033D01*
G01X-792817Y-557500D02*
Y-550500D01*
X-788983Y-557500D01*
Y-550500D01*
G01X-785933Y-557500D02*
Y-550500D01*
X-784267D01*
X-783600Y-550850D01*
X-783100Y-551317D01*
X-782683Y-552017D01*
X-782350Y-552833D01*
X-782267Y-554000D01*
X-782350Y-555167D01*
X-782683Y-555983D01*
X-783100Y-556684D01*
X-783600Y-557150D01*
X-784267Y-557500D01*
X-785933D01*
G01X-771500Y-550500D02*
X-769500D01*
G01X-770500D02*
Y-557500D01*
G01X-771500D02*
X-769500D01*
G01X-763700Y-550500D02*
Y-557500D01*
G01X-765617Y-550500D02*
X-761783D01*
G01X-758650Y-556567D02*
X-757983Y-557150D01*
X-757233Y-557500D01*
X-756567D01*
X-755900Y-557150D01*
X-755400Y-556567D01*
X-755150Y-555750D01*
X-755317Y-554933D01*
X-755733Y-554233D01*
X-756483Y-553767D01*
X-757483Y-553533D01*
X-758067Y-553067D01*
X-758317Y-552250D01*
X-758150Y-551433D01*
X-757733Y-550850D01*
X-757150Y-550500D01*
X-756567D01*
X-755983Y-550733D01*
X-755483Y-551317D01*
G01X-741467Y-551083D02*
X-741967Y-550733D01*
X-742550Y-550500D01*
X-743217D01*
X-743967Y-550850D01*
X-744550Y-551433D01*
X-744967Y-552133D01*
X-745300Y-553300D01*
X-745383Y-554350D01*
X-745217Y-555400D01*
X-744967Y-556100D01*
X-744467Y-556800D01*
X-743883Y-557267D01*
X-743300Y-557500D01*
X-742717D01*
X-742133Y-557267D01*
X-741633Y-556917D01*
X-741217Y-556450D01*
G01X-736500Y-557500D02*
X-737167Y-557383D01*
X-737750Y-556917D01*
X-738250Y-556217D01*
X-738583Y-555400D01*
X-738750Y-554467D01*
Y-553533D01*
X-738583Y-552600D01*
X-738250Y-551783D01*
X-737750Y-551083D01*
X-737167Y-550617D01*
X-736500Y-550500D01*
X-735833Y-550617D01*
X-735250Y-551083D01*
X-734750Y-551783D01*
X-734417Y-552600D01*
X-734250Y-553533D01*
Y-554467D01*
X-734417Y-555400D01*
X-734750Y-556217D01*
X-735250Y-556917D01*
X-735833Y-557383D01*
X-736500Y-557500D01*
G01X-731617D02*
Y-550500D01*
X-727783Y-557500D01*
Y-550500D01*
G01X-722900D02*
Y-557500D01*
G01X-724817Y-550500D02*
X-720983D01*
G01X-714433Y-557500D02*
X-717767D01*
Y-550500D01*
X-714433D01*
G01X-715767Y-553883D02*
X-717767D01*
G01X-711217Y-557500D02*
Y-550500D01*
X-707383Y-557500D01*
Y-550500D01*
G01X-702500D02*
Y-557500D01*
G01X-704417Y-550500D02*
X-700583D01*
G01X-697450Y-556567D02*
X-696783Y-557150D01*
X-696033Y-557500D01*
X-695367D01*
X-694700Y-557150D01*
X-694200Y-556567D01*
X-693950Y-555750D01*
X-694117Y-554933D01*
X-694533Y-554233D01*
X-695283Y-553767D01*
X-696283Y-553533D01*
X-696867Y-553067D01*
X-697117Y-552250D01*
X-696950Y-551433D01*
X-696533Y-550850D01*
X-695950Y-550500D01*
X-695367D01*
X-694783Y-550733D01*
X-694283Y-551317D01*
G01X-684267Y-557500D02*
Y-550500D01*
X-682100Y-556333D01*
X-679933Y-550500D01*
Y-557500D01*
G01X-677383D02*
X-675300Y-550500D01*
X-673217Y-557500D01*
G01X-673967Y-555050D02*
X-676633D01*
G01X-668500Y-557500D02*
Y-554350D01*
X-670167Y-550500D01*
G01X-666833D02*
X-668500Y-554350D01*
G01X-656817Y-557500D02*
Y-550500D01*
X-652983Y-557500D01*
Y-550500D01*
G01X-648100Y-557500D02*
X-648767Y-557383D01*
X-649350Y-556917D01*
X-649850Y-556217D01*
X-650183Y-555400D01*
X-650350Y-554467D01*
Y-553533D01*
X-650183Y-552600D01*
X-649850Y-551783D01*
X-649350Y-551083D01*
X-648767Y-550617D01*
X-648100Y-550500D01*
X-647433Y-550617D01*
X-646850Y-551083D01*
X-646350Y-551783D01*
X-646017Y-552600D01*
X-645850Y-553533D01*
Y-554467D01*
X-646017Y-555400D01*
X-646350Y-556217D01*
X-646850Y-556917D01*
X-647433Y-557383D01*
X-648100Y-557500D01*
G01X-641300Y-550500D02*
Y-557500D01*
G01X-643217Y-550500D02*
X-639383D01*
G01X-627033Y-553767D02*
X-626700Y-553417D01*
X-626450Y-552833D01*
X-626283Y-552017D01*
X-626450Y-551317D01*
X-626783Y-550850D01*
X-627367Y-550500D01*
X-629617D01*
Y-557500D01*
X-626867D01*
X-626283Y-557033D01*
X-625950Y-556333D01*
X-625783Y-555517D01*
X-625950Y-554700D01*
X-626450Y-554000D01*
X-627033Y-553767D01*
X-629617D01*
G01X-619233Y-557500D02*
X-622567D01*
Y-550500D01*
X-619233D01*
G01X-620567Y-553883D02*
X-622567D01*
G01X-870667Y-536083D02*
X-871167Y-535733D01*
X-871750Y-535500D01*
X-872417D01*
X-873167Y-535850D01*
X-873750Y-536433D01*
X-874167Y-537133D01*
X-874500Y-538300D01*
X-874583Y-539350D01*
X-874417Y-540400D01*
X-874167Y-541100D01*
X-873667Y-541800D01*
X-873083Y-542267D01*
X-872500Y-542500D01*
X-871917D01*
X-871333Y-542267D01*
X-870833Y-541917D01*
X-870417Y-541450D01*
G01X-865700Y-542500D02*
X-866367Y-542383D01*
X-866950Y-541917D01*
X-867450Y-541217D01*
X-867783Y-540400D01*
X-867950Y-539467D01*
Y-538533D01*
X-867783Y-537600D01*
X-867450Y-536783D01*
X-866950Y-536083D01*
X-866367Y-535617D01*
X-865700Y-535500D01*
X-865033Y-535617D01*
X-864450Y-536083D01*
X-863950Y-536783D01*
X-863617Y-537600D01*
X-863450Y-538533D01*
Y-539467D01*
X-863617Y-540400D01*
X-863950Y-541217D01*
X-864450Y-541917D01*
X-865033Y-542383D01*
X-865700Y-542500D01*
G01X-860567D02*
Y-535500D01*
X-858483D01*
X-857817Y-535850D01*
X-857400Y-536317D01*
X-857233Y-537250D01*
X-857400Y-538183D01*
X-857900Y-538767D01*
X-858483Y-539117D01*
X-860567D01*
G01X-858483D02*
X-857233Y-542500D01*
G01X-853767D02*
Y-535500D01*
X-851767D01*
X-851100Y-535850D01*
X-850600Y-536667D01*
X-850433Y-537600D01*
X-850600Y-538533D01*
X-851017Y-539233D01*
X-851767Y-539584D01*
X-853767D01*
G01X-845300Y-542500D02*
X-845967Y-542383D01*
X-846550Y-541917D01*
X-847050Y-541217D01*
X-847383Y-540400D01*
X-847550Y-539467D01*
Y-538533D01*
X-847383Y-537600D01*
X-847050Y-536783D01*
X-846550Y-536083D01*
X-845967Y-535617D01*
X-845300Y-535500D01*
X-844633Y-535617D01*
X-844050Y-536083D01*
X-843550Y-536783D01*
X-843217Y-537600D01*
X-843050Y-538533D01*
Y-539467D01*
X-843217Y-540400D01*
X-843550Y-541217D01*
X-844050Y-541917D01*
X-844633Y-542383D01*
X-845300Y-542500D01*
G01X-840167D02*
Y-535500D01*
X-838083D01*
X-837417Y-535850D01*
X-837000Y-536317D01*
X-836833Y-537250D01*
X-837000Y-538183D01*
X-837500Y-538767D01*
X-838083Y-539117D01*
X-840167D01*
G01X-838083D02*
X-836833Y-542500D01*
G01X-833783D02*
X-831700Y-535500D01*
X-829617Y-542500D01*
G01X-830367Y-540050D02*
X-833033D01*
G01X-824900Y-535500D02*
Y-542500D01*
G01X-826817Y-535500D02*
X-822983D01*
G01X-819100D02*
X-817100D01*
G01X-818100D02*
Y-542500D01*
G01X-819100D02*
X-817100D01*
G01X-811300D02*
X-811967Y-542383D01*
X-812550Y-541917D01*
X-813050Y-541217D01*
X-813383Y-540400D01*
X-813550Y-539467D01*
Y-538533D01*
X-813383Y-537600D01*
X-813050Y-536783D01*
X-812550Y-536083D01*
X-811967Y-535617D01*
X-811300Y-535500D01*
X-810633Y-535617D01*
X-810050Y-536083D01*
X-809550Y-536783D01*
X-809217Y-537600D01*
X-809050Y-538533D01*
Y-539467D01*
X-809217Y-540400D01*
X-809550Y-541217D01*
X-810050Y-541917D01*
X-810633Y-542383D01*
X-811300Y-542500D01*
G01X-806417D02*
Y-535500D01*
X-802583Y-542500D01*
Y-535500D01*
G01X-797700Y-542733D02*
X-797867Y-542617D01*
Y-542383D01*
X-797700Y-542267D01*
X-797533Y-542383D01*
Y-542617D01*
X-797700Y-542733D01*
G01X-784100Y-535500D02*
Y-542500D01*
G01X-786017Y-535500D02*
X-782183D01*
G01X-779050Y-542500D02*
Y-535500D01*
G01X-775550D02*
Y-542500D01*
G01Y-539000D02*
X-779050D01*
G01X-771500Y-535500D02*
X-769500D01*
G01X-770500D02*
Y-542500D01*
G01X-771500D02*
X-769500D01*
G01X-765450Y-541567D02*
X-764783Y-542150D01*
X-764033Y-542500D01*
X-763367D01*
X-762700Y-542150D01*
X-762200Y-541567D01*
X-761950Y-540750D01*
X-762117Y-539933D01*
X-762533Y-539233D01*
X-763283Y-538767D01*
X-764283Y-538533D01*
X-764867Y-538067D01*
X-765117Y-537250D01*
X-764950Y-536433D01*
X-764533Y-535850D01*
X-763950Y-535500D01*
X-763367D01*
X-762783Y-535733D01*
X-762283Y-536317D01*
G01X-751933Y-542500D02*
Y-535500D01*
X-750267D01*
X-749600Y-535850D01*
X-749100Y-536317D01*
X-748683Y-537017D01*
X-748350Y-537833D01*
X-748267Y-539000D01*
X-748350Y-540167D01*
X-748683Y-540983D01*
X-749100Y-541684D01*
X-749600Y-542150D01*
X-750267Y-542500D01*
X-751933D01*
G01X-744967D02*
Y-535500D01*
X-742883D01*
X-742217Y-535850D01*
X-741800Y-536317D01*
X-741633Y-537250D01*
X-741800Y-538183D01*
X-742300Y-538767D01*
X-742883Y-539117D01*
X-744967D01*
G01X-742883D02*
X-741633Y-542500D01*
G01X-738583D02*
X-736500Y-535500D01*
X-734417Y-542500D01*
G01X-735167Y-540050D02*
X-737833D01*
G01X-732200Y-535500D02*
X-731033Y-542500D01*
X-729700Y-535500D01*
X-728367Y-542500D01*
X-727200Y-535500D01*
G01X-723900D02*
X-721900D01*
G01X-722900D02*
Y-542500D01*
G01X-723900D02*
X-721900D01*
G01X-718017D02*
Y-535500D01*
X-714183Y-542500D01*
Y-535500D01*
G01X-708800Y-539000D02*
X-707133D01*
Y-541100D01*
X-707633Y-541800D01*
X-708217Y-542267D01*
X-709050Y-542500D01*
X-709883Y-542267D01*
X-710467Y-541800D01*
X-710967Y-541100D01*
X-711300Y-540283D01*
X-711467Y-539350D01*
Y-538533D01*
X-711300Y-537833D01*
X-710967Y-537017D01*
X-710467Y-536317D01*
X-709967Y-535850D01*
X-709300Y-535500D01*
X-708717D01*
X-708050Y-535733D01*
X-707550Y-536200D01*
G01X-696700Y-535500D02*
X-694700D01*
G01X-695700D02*
Y-542500D01*
G01X-696700D02*
X-694700D01*
G01X-690650Y-541567D02*
X-689983Y-542150D01*
X-689233Y-542500D01*
X-688567D01*
X-687900Y-542150D01*
X-687400Y-541567D01*
X-687150Y-540750D01*
X-687317Y-539933D01*
X-687733Y-539233D01*
X-688483Y-538767D01*
X-689483Y-538533D01*
X-690067Y-538067D01*
X-690317Y-537250D01*
X-690150Y-536433D01*
X-689733Y-535850D01*
X-689150Y-535500D01*
X-688567D01*
X-687983Y-535733D01*
X-687483Y-536317D01*
G01X-676967Y-542500D02*
Y-535500D01*
X-674883D01*
X-674217Y-535850D01*
X-673800Y-536317D01*
X-673633Y-537250D01*
X-673800Y-538183D01*
X-674300Y-538767D01*
X-674883Y-539117D01*
X-676967D01*
G01X-674883D02*
X-673633Y-542500D01*
G01X-666833D02*
X-670167D01*
Y-535500D01*
X-666833D01*
G01X-668167Y-538883D02*
X-670167D01*
G01X-659867Y-536083D02*
X-660367Y-535733D01*
X-660950Y-535500D01*
X-661617D01*
X-662367Y-535850D01*
X-662950Y-536433D01*
X-663367Y-537133D01*
X-663700Y-538300D01*
X-663783Y-539350D01*
X-663617Y-540400D01*
X-663367Y-541100D01*
X-662867Y-541800D01*
X-662283Y-542267D01*
X-661700Y-542500D01*
X-661117D01*
X-660533Y-542267D01*
X-660033Y-541917D01*
X-659617Y-541450D01*
G01X-653233Y-542500D02*
X-656567D01*
Y-535500D01*
X-653233D01*
G01X-654567Y-538883D02*
X-656567D01*
G01X-649100Y-535500D02*
X-647100D01*
G01X-648100D02*
Y-542500D01*
G01X-649100D02*
X-647100D01*
G01X-643383Y-535500D02*
X-641300Y-542500D01*
X-639217Y-535500D01*
G01X-632833Y-542500D02*
X-636167D01*
Y-535500D01*
X-632833D01*
G01X-634167Y-538883D02*
X-636167D01*
G01X-629533Y-542500D02*
Y-535500D01*
X-627867D01*
X-627200Y-535850D01*
X-626700Y-536317D01*
X-626283Y-537017D01*
X-625950Y-537833D01*
X-625867Y-539000D01*
X-625950Y-540167D01*
X-626283Y-540983D01*
X-626700Y-541684D01*
X-627200Y-542150D01*
X-627867Y-542500D01*
X-629533D01*
G01X-615100Y-535500D02*
X-613100D01*
G01X-614100D02*
Y-542500D01*
G01X-615100D02*
X-613100D01*
G01X-609217D02*
Y-535500D01*
X-605383Y-542500D01*
Y-535500D01*
G01X-872500Y-520500D02*
Y-527500D01*
G01X-874417Y-520500D02*
X-870583D01*
G01X-867450Y-527500D02*
Y-520500D01*
G01X-863950D02*
Y-527500D01*
G01Y-524000D02*
X-867450D01*
G01X-857233Y-527500D02*
X-860567D01*
Y-520500D01*
X-857233D01*
G01X-858567Y-523883D02*
X-860567D01*
G01X-846967Y-527500D02*
Y-520500D01*
X-844967D01*
X-844300Y-520850D01*
X-843800Y-521667D01*
X-843633Y-522600D01*
X-843800Y-523533D01*
X-844217Y-524233D01*
X-844967Y-524584D01*
X-846967D01*
G01X-840167Y-527500D02*
Y-520500D01*
X-838083D01*
X-837417Y-520850D01*
X-837000Y-521317D01*
X-836833Y-522250D01*
X-837000Y-523183D01*
X-837500Y-523767D01*
X-838083Y-524117D01*
X-840167D01*
G01X-838083D02*
X-836833Y-527500D01*
G01X-831700D02*
X-832367Y-527383D01*
X-832950Y-526917D01*
X-833450Y-526217D01*
X-833783Y-525400D01*
X-833950Y-524467D01*
Y-523533D01*
X-833783Y-522600D01*
X-833450Y-521783D01*
X-832950Y-521083D01*
X-832367Y-520617D01*
X-831700Y-520500D01*
X-831033Y-520617D01*
X-830450Y-521083D01*
X-829950Y-521783D01*
X-829617Y-522600D01*
X-829450Y-523533D01*
Y-524467D01*
X-829617Y-525400D01*
X-829950Y-526217D01*
X-830450Y-526917D01*
X-831033Y-527383D01*
X-831700Y-527500D01*
G01X-826567D02*
Y-520500D01*
X-824567D01*
X-823900Y-520850D01*
X-823400Y-521667D01*
X-823233Y-522600D01*
X-823400Y-523533D01*
X-823817Y-524233D01*
X-824567Y-524584D01*
X-826567D01*
G01X-819767Y-527500D02*
Y-520500D01*
X-817683D01*
X-817017Y-520850D01*
X-816600Y-521317D01*
X-816433Y-522250D01*
X-816600Y-523183D01*
X-817100Y-523767D01*
X-817683Y-524117D01*
X-819767D01*
G01X-817683D02*
X-816433Y-527500D01*
G01X-812300Y-520500D02*
X-810300D01*
G01X-811300D02*
Y-527500D01*
G01X-812300D02*
X-810300D01*
G01X-802833D02*
X-806167D01*
Y-520500D01*
X-802833D01*
G01X-804167Y-523883D02*
X-806167D01*
G01X-797700Y-520500D02*
Y-527500D01*
G01X-799617Y-520500D02*
X-795783D01*
G01X-792983Y-527500D02*
X-790900Y-520500D01*
X-788817Y-527500D01*
G01X-789567Y-525050D02*
X-792233D01*
G01X-785767Y-527500D02*
Y-520500D01*
X-783683D01*
X-783017Y-520850D01*
X-782600Y-521317D01*
X-782433Y-522250D01*
X-782600Y-523183D01*
X-783100Y-523767D01*
X-783683Y-524117D01*
X-785767D01*
G01X-783683D02*
X-782433Y-527500D01*
G01X-777300D02*
Y-524350D01*
X-778967Y-520500D01*
G01X-775633D02*
X-777300Y-524350D01*
G01X-765367Y-527500D02*
Y-520500D01*
X-763367D01*
X-762700Y-520850D01*
X-762200Y-521667D01*
X-762033Y-522600D01*
X-762200Y-523533D01*
X-762617Y-524233D01*
X-763367Y-524584D01*
X-765367D01*
G01X-758567Y-527500D02*
Y-520500D01*
X-756483D01*
X-755817Y-520850D01*
X-755400Y-521317D01*
X-755233Y-522250D01*
X-755400Y-523183D01*
X-755900Y-523767D01*
X-756483Y-524117D01*
X-758567D01*
G01X-756483D02*
X-755233Y-527500D01*
G01X-750100D02*
X-750767Y-527383D01*
X-751350Y-526917D01*
X-751850Y-526217D01*
X-752183Y-525400D01*
X-752350Y-524467D01*
Y-523533D01*
X-752183Y-522600D01*
X-751850Y-521783D01*
X-751350Y-521083D01*
X-750767Y-520617D01*
X-750100Y-520500D01*
X-749433Y-520617D01*
X-748850Y-521083D01*
X-748350Y-521783D01*
X-748017Y-522600D01*
X-747850Y-523533D01*
Y-524467D01*
X-748017Y-525400D01*
X-748350Y-526217D01*
X-748850Y-526917D01*
X-749433Y-527383D01*
X-750100Y-527500D01*
G01X-744967D02*
Y-520500D01*
X-742967D01*
X-742300Y-520850D01*
X-741800Y-521667D01*
X-741633Y-522600D01*
X-741800Y-523533D01*
X-742217Y-524233D01*
X-742967Y-524584D01*
X-744967D01*
G01X-734833Y-527500D02*
X-738167D01*
Y-520500D01*
X-734833D01*
G01X-736167Y-523883D02*
X-738167D01*
G01X-731367Y-527500D02*
Y-520500D01*
X-729283D01*
X-728617Y-520850D01*
X-728200Y-521317D01*
X-728033Y-522250D01*
X-728200Y-523183D01*
X-728700Y-523767D01*
X-729283Y-524117D01*
X-731367D01*
G01X-729283D02*
X-728033Y-527500D01*
G01X-722900Y-520500D02*
Y-527500D01*
G01X-724817Y-520500D02*
X-720983D01*
G01X-716100Y-527500D02*
Y-524350D01*
X-717767Y-520500D01*
G01X-714433D02*
X-716100Y-524350D01*
G01X-702500Y-527500D02*
X-703167Y-527383D01*
X-703750Y-526917D01*
X-704250Y-526217D01*
X-704583Y-525400D01*
X-704750Y-524467D01*
Y-523533D01*
X-704583Y-522600D01*
X-704250Y-521783D01*
X-703750Y-521083D01*
X-703167Y-520617D01*
X-702500Y-520500D01*
X-701833Y-520617D01*
X-701250Y-521083D01*
X-700750Y-521783D01*
X-700417Y-522600D01*
X-700250Y-523533D01*
Y-524467D01*
X-700417Y-525400D01*
X-700750Y-526217D01*
X-701250Y-526917D01*
X-701833Y-527383D01*
X-702500Y-527500D01*
G01X-697283D02*
Y-520500D01*
X-694117D01*
G01X-695283Y-523883D02*
X-697283D01*
G01X-684267Y-527500D02*
Y-520500D01*
X-682100Y-526333D01*
X-679933Y-520500D01*
Y-527500D01*
G01X-676300Y-520500D02*
X-674300D01*
G01X-675300D02*
Y-527500D01*
G01X-676300D02*
X-674300D01*
G01X-666667Y-521083D02*
X-667167Y-520733D01*
X-667750Y-520500D01*
X-668417D01*
X-669167Y-520850D01*
X-669750Y-521433D01*
X-670167Y-522133D01*
X-670500Y-523300D01*
X-670583Y-524350D01*
X-670417Y-525400D01*
X-670167Y-526100D01*
X-669667Y-526800D01*
X-669083Y-527267D01*
X-668500Y-527500D01*
X-667917D01*
X-667333Y-527267D01*
X-666833Y-526917D01*
X-666417Y-526450D01*
G01X-663367Y-527500D02*
Y-520500D01*
X-661283D01*
X-660617Y-520850D01*
X-660200Y-521317D01*
X-660033Y-522250D01*
X-660200Y-523183D01*
X-660700Y-523767D01*
X-661283Y-524117D01*
X-663367D01*
G01X-661283D02*
X-660033Y-527500D01*
G01X-654900D02*
X-655567Y-527383D01*
X-656150Y-526917D01*
X-656650Y-526217D01*
X-656983Y-525400D01*
X-657150Y-524467D01*
Y-523533D01*
X-656983Y-522600D01*
X-656650Y-521783D01*
X-656150Y-521083D01*
X-655567Y-520617D01*
X-654900Y-520500D01*
X-654233Y-520617D01*
X-653650Y-521083D01*
X-653150Y-521783D01*
X-652817Y-522600D01*
X-652650Y-523533D01*
Y-524467D01*
X-652817Y-525400D01*
X-653150Y-526217D01*
X-653650Y-526917D01*
X-654233Y-527383D01*
X-654900Y-527500D01*
G01X-649850Y-526567D02*
X-649183Y-527150D01*
X-648433Y-527500D01*
X-647767D01*
X-647100Y-527150D01*
X-646600Y-526567D01*
X-646350Y-525750D01*
X-646517Y-524933D01*
X-646933Y-524233D01*
X-647683Y-523767D01*
X-648683Y-523533D01*
X-649267Y-523067D01*
X-649517Y-522250D01*
X-649350Y-521433D01*
X-648933Y-520850D01*
X-648350Y-520500D01*
X-647767D01*
X-647183Y-520733D01*
X-646683Y-521317D01*
G01X-641300Y-527500D02*
X-641967Y-527383D01*
X-642550Y-526917D01*
X-643050Y-526217D01*
X-643383Y-525400D01*
X-643550Y-524467D01*
Y-523533D01*
X-643383Y-522600D01*
X-643050Y-521783D01*
X-642550Y-521083D01*
X-641967Y-520617D01*
X-641300Y-520500D01*
X-640633Y-520617D01*
X-640050Y-521083D01*
X-639550Y-521783D01*
X-639217Y-522600D01*
X-639050Y-523533D01*
Y-524467D01*
X-639217Y-525400D01*
X-639550Y-526217D01*
X-640050Y-526917D01*
X-640633Y-527383D01*
X-641300Y-527500D01*
G01X-636083D02*
Y-520500D01*
X-632917D01*
G01X-634083Y-523883D02*
X-636083D01*
G01X-627700Y-520500D02*
Y-527500D01*
G01X-629617Y-520500D02*
X-625783D01*
G01X-872500Y-505500D02*
Y-512500D01*
G01X-874417Y-505500D02*
X-870583D01*
G01X-867450Y-512500D02*
Y-505500D01*
G01X-863950D02*
Y-512500D01*
G01Y-509000D02*
X-867450D01*
G01X-859900Y-505500D02*
X-857900D01*
G01X-858900D02*
Y-512500D01*
G01X-859900D02*
X-857900D01*
G01X-853850Y-511567D02*
X-853183Y-512150D01*
X-852433Y-512500D01*
X-851767D01*
X-851100Y-512150D01*
X-850600Y-511567D01*
X-850350Y-510750D01*
X-850517Y-509933D01*
X-850933Y-509233D01*
X-851683Y-508767D01*
X-852683Y-508533D01*
X-853267Y-508067D01*
X-853517Y-507250D01*
X-853350Y-506433D01*
X-852933Y-505850D01*
X-852350Y-505500D01*
X-851767D01*
X-851183Y-505733D01*
X-850683Y-506317D01*
G01X-840333Y-512500D02*
Y-505500D01*
X-838667D01*
X-838000Y-505850D01*
X-837500Y-506317D01*
X-837083Y-507017D01*
X-836750Y-507833D01*
X-836667Y-509000D01*
X-836750Y-510167D01*
X-837083Y-510983D01*
X-837500Y-511684D01*
X-838000Y-512150D01*
X-838667Y-512500D01*
X-840333D01*
G01X-833367D02*
Y-505500D01*
X-831283D01*
X-830617Y-505850D01*
X-830200Y-506317D01*
X-830033Y-507250D01*
X-830200Y-508183D01*
X-830700Y-508767D01*
X-831283Y-509117D01*
X-833367D01*
G01X-831283D02*
X-830033Y-512500D01*
G01X-826983D02*
X-824900Y-505500D01*
X-822817Y-512500D01*
G01X-823567Y-510050D02*
X-826233D01*
G01X-820600Y-505500D02*
X-819433Y-512500D01*
X-818100Y-505500D01*
X-816767Y-512500D01*
X-815600Y-505500D01*
G01X-812300D02*
X-810300D01*
G01X-811300D02*
Y-512500D01*
G01X-812300D02*
X-810300D01*
G01X-806417D02*
Y-505500D01*
X-802583Y-512500D01*
Y-505500D01*
G01X-797200Y-509000D02*
X-795533D01*
Y-511100D01*
X-796033Y-511800D01*
X-796617Y-512267D01*
X-797450Y-512500D01*
X-798283Y-512267D01*
X-798867Y-511800D01*
X-799367Y-511100D01*
X-799700Y-510283D01*
X-799867Y-509350D01*
Y-508533D01*
X-799700Y-507833D01*
X-799367Y-507017D01*
X-798867Y-506317D01*
X-798367Y-505850D01*
X-797700Y-505500D01*
X-797117D01*
X-796450Y-505733D01*
X-795950Y-506200D01*
G01X-782267Y-506083D02*
X-782767Y-505733D01*
X-783350Y-505500D01*
X-784017D01*
X-784767Y-505850D01*
X-785350Y-506433D01*
X-785767Y-507133D01*
X-786100Y-508300D01*
X-786183Y-509350D01*
X-786017Y-510400D01*
X-785767Y-511100D01*
X-785267Y-511800D01*
X-784683Y-512267D01*
X-784100Y-512500D01*
X-783517D01*
X-782933Y-512267D01*
X-782433Y-511917D01*
X-782017Y-511450D01*
G01X-777300Y-512500D02*
X-777967Y-512383D01*
X-778550Y-511917D01*
X-779050Y-511217D01*
X-779383Y-510400D01*
X-779550Y-509467D01*
Y-508533D01*
X-779383Y-507600D01*
X-779050Y-506783D01*
X-778550Y-506083D01*
X-777967Y-505617D01*
X-777300Y-505500D01*
X-776633Y-505617D01*
X-776050Y-506083D01*
X-775550Y-506783D01*
X-775217Y-507600D01*
X-775050Y-508533D01*
Y-509467D01*
X-775217Y-510400D01*
X-775550Y-511217D01*
X-776050Y-511917D01*
X-776633Y-512383D01*
X-777300Y-512500D01*
G01X-772417D02*
Y-505500D01*
X-768583Y-512500D01*
Y-505500D01*
G01X-763700D02*
Y-512500D01*
G01X-765617Y-505500D02*
X-761783D01*
G01X-758983Y-512500D02*
X-756900Y-505500D01*
X-754817Y-512500D01*
G01X-755567Y-510050D02*
X-758233D01*
G01X-751100Y-505500D02*
X-749100D01*
G01X-750100D02*
Y-512500D01*
G01X-751100D02*
X-749100D01*
G01X-745217D02*
Y-505500D01*
X-741383Y-512500D01*
Y-505500D01*
G01X-738250Y-511567D02*
X-737583Y-512150D01*
X-736833Y-512500D01*
X-736167D01*
X-735500Y-512150D01*
X-735000Y-511567D01*
X-734750Y-510750D01*
X-734917Y-509933D01*
X-735333Y-509233D01*
X-736083Y-508767D01*
X-737083Y-508533D01*
X-737667Y-508067D01*
X-737917Y-507250D01*
X-737750Y-506433D01*
X-737333Y-505850D01*
X-736750Y-505500D01*
X-736167D01*
X-735583Y-505733D01*
X-735083Y-506317D01*
G01X-723900Y-505500D02*
X-721900D01*
G01X-722900D02*
Y-512500D01*
G01X-723900D02*
X-721900D01*
G01X-718017D02*
Y-505500D01*
X-714183Y-512500D01*
Y-505500D01*
G01X-710883Y-512500D02*
Y-505500D01*
X-707717D01*
G01X-708883Y-508883D02*
X-710883D01*
G01X-702500Y-512500D02*
X-703167Y-512383D01*
X-703750Y-511917D01*
X-704250Y-511217D01*
X-704583Y-510400D01*
X-704750Y-509467D01*
Y-508533D01*
X-704583Y-507600D01*
X-704250Y-506783D01*
X-703750Y-506083D01*
X-703167Y-505617D01*
X-702500Y-505500D01*
X-701833Y-505617D01*
X-701250Y-506083D01*
X-700750Y-506783D01*
X-700417Y-507600D01*
X-700250Y-508533D01*
Y-509467D01*
X-700417Y-510400D01*
X-700750Y-511217D01*
X-701250Y-511917D01*
X-701833Y-512383D01*
X-702500Y-512500D01*
G01X-697367D02*
Y-505500D01*
X-695283D01*
X-694617Y-505850D01*
X-694200Y-506317D01*
X-694033Y-507250D01*
X-694200Y-508183D01*
X-694700Y-508767D01*
X-695283Y-509117D01*
X-697367D01*
G01X-695283D02*
X-694033Y-512500D01*
G01X-691067D02*
Y-505500D01*
X-688900Y-511333D01*
X-686733Y-505500D01*
Y-512500D01*
G01X-684183D02*
X-682100Y-505500D01*
X-680017Y-512500D01*
G01X-680767Y-510050D02*
X-683433D01*
G01X-675300Y-505500D02*
Y-512500D01*
G01X-677217Y-505500D02*
X-673383D01*
G01X-669500D02*
X-667500D01*
G01X-668500D02*
Y-512500D01*
G01X-669500D02*
X-667500D01*
G01X-661700D02*
X-662367Y-512383D01*
X-662950Y-511917D01*
X-663450Y-511217D01*
X-663783Y-510400D01*
X-663950Y-509467D01*
Y-508533D01*
X-663783Y-507600D01*
X-663450Y-506783D01*
X-662950Y-506083D01*
X-662367Y-505617D01*
X-661700Y-505500D01*
X-661033Y-505617D01*
X-660450Y-506083D01*
X-659950Y-506783D01*
X-659617Y-507600D01*
X-659450Y-508533D01*
Y-509467D01*
X-659617Y-510400D01*
X-659950Y-511217D01*
X-660450Y-511917D01*
X-661033Y-512383D01*
X-661700Y-512500D01*
G01X-656817D02*
Y-505500D01*
X-652983Y-512500D01*
Y-505500D01*
G01X-643800D02*
X-642633Y-512500D01*
X-641300Y-505500D01*
X-639967Y-512500D01*
X-638800Y-505500D01*
G01X-636250Y-512500D02*
Y-505500D01*
G01X-632750D02*
Y-512500D01*
G01Y-509000D02*
X-636250D01*
G01X-628700Y-505500D02*
X-626700D01*
G01X-627700D02*
Y-512500D01*
G01X-628700D02*
X-626700D01*
G01X-619067Y-506083D02*
X-619567Y-505733D01*
X-620150Y-505500D01*
X-620817D01*
X-621567Y-505850D01*
X-622150Y-506433D01*
X-622567Y-507133D01*
X-622900Y-508300D01*
X-622983Y-509350D01*
X-622817Y-510400D01*
X-622567Y-511100D01*
X-622067Y-511800D01*
X-621483Y-512267D01*
X-620900Y-512500D01*
X-620317D01*
X-619733Y-512267D01*
X-619233Y-511917D01*
X-618817Y-511450D01*
G01X-615850Y-512500D02*
Y-505500D01*
G01X-612350D02*
Y-512500D01*
G01Y-509000D02*
X-615850D01*
G01X-601500Y-505500D02*
X-599500D01*
G01X-600500D02*
Y-512500D01*
G01X-601500D02*
X-599500D01*
G01X-595450Y-511567D02*
X-594783Y-512150D01*
X-594033Y-512500D01*
X-593367D01*
X-592700Y-512150D01*
X-592200Y-511567D01*
X-591950Y-510750D01*
X-592117Y-509933D01*
X-592533Y-509233D01*
X-593283Y-508767D01*
X-594283Y-508533D01*
X-594867Y-508067D01*
X-595117Y-507250D01*
X-594950Y-506433D01*
X-594533Y-505850D01*
X-593950Y-505500D01*
X-593367D01*
X-592783Y-505733D01*
X-592283Y-506317D01*
G01X-858133Y-452500D02*
Y-445500D01*
X-856467D01*
X-855800Y-445850D01*
X-855300Y-446317D01*
X-854883Y-447017D01*
X-854550Y-447833D01*
X-854467Y-449000D01*
X-854550Y-450167D01*
X-854883Y-450983D01*
X-855300Y-451684D01*
X-855800Y-452150D01*
X-856467Y-452500D01*
X-858133D01*
G01X-847833D02*
X-851167D01*
Y-445500D01*
X-847833D01*
G01X-849167Y-448883D02*
X-851167D01*
G01X-844450Y-451567D02*
X-843783Y-452150D01*
X-843033Y-452500D01*
X-842367D01*
X-841700Y-452150D01*
X-841200Y-451567D01*
X-840950Y-450750D01*
X-841117Y-449933D01*
X-841533Y-449233D01*
X-842283Y-448767D01*
X-843283Y-448533D01*
X-843867Y-448067D01*
X-844117Y-447250D01*
X-843950Y-446433D01*
X-843533Y-445850D01*
X-842950Y-445500D01*
X-842367D01*
X-841783Y-445733D01*
X-841283Y-446317D01*
G01X-836900Y-445500D02*
X-834900D01*
G01X-835900D02*
Y-452500D01*
G01X-836900D02*
X-834900D01*
G01X-828600Y-449000D02*
X-826933D01*
Y-451100D01*
X-827433Y-451800D01*
X-828017Y-452267D01*
X-828850Y-452500D01*
X-829683Y-452267D01*
X-830267Y-451800D01*
X-830767Y-451100D01*
X-831100Y-450283D01*
X-831267Y-449350D01*
Y-448533D01*
X-831100Y-447833D01*
X-830767Y-447017D01*
X-830267Y-446317D01*
X-829767Y-445850D01*
X-829100Y-445500D01*
X-828517D01*
X-827850Y-445733D01*
X-827350Y-446200D01*
G01X-824217Y-452500D02*
Y-445500D01*
X-820383Y-452500D01*
Y-445500D01*
G01X-813833Y-452500D02*
X-817167D01*
Y-445500D01*
X-813833D01*
G01X-815167Y-448883D02*
X-817167D01*
G01X-810367Y-452500D02*
Y-445500D01*
X-808283D01*
X-807617Y-445850D01*
X-807200Y-446317D01*
X-807033Y-447250D01*
X-807200Y-448183D01*
X-807700Y-448767D01*
X-808283Y-449117D01*
X-810367D01*
G01X-808283D02*
X-807033Y-452500D01*
G01X-858133D02*
Y-445500D01*
X-856467D01*
X-855800Y-445850D01*
X-855300Y-446317D01*
X-854883Y-447017D01*
X-854550Y-447833D01*
X-854467Y-449000D01*
X-854550Y-450167D01*
X-854883Y-450983D01*
X-855300Y-451684D01*
X-855800Y-452150D01*
X-856467Y-452500D01*
X-858133D01*
G01X-847833D02*
X-851167D01*
Y-445500D01*
X-847833D01*
G01X-849167Y-448883D02*
X-851167D01*
G01X-844450Y-451567D02*
X-843783Y-452150D01*
X-843033Y-452500D01*
X-842367D01*
X-841700Y-452150D01*
X-841200Y-451567D01*
X-840950Y-450750D01*
X-841117Y-449933D01*
X-841533Y-449233D01*
X-842283Y-448767D01*
X-843283Y-448533D01*
X-843867Y-448067D01*
X-844117Y-447250D01*
X-843950Y-446433D01*
X-843533Y-445850D01*
X-842950Y-445500D01*
X-842367D01*
X-841783Y-445733D01*
X-841283Y-446317D01*
G01X-836900Y-445500D02*
X-834900D01*
G01X-835900D02*
Y-452500D01*
G01X-836900D02*
X-834900D01*
G01X-828600Y-449000D02*
X-826933D01*
Y-451100D01*
X-827433Y-451800D01*
X-828017Y-452267D01*
X-828850Y-452500D01*
X-829683Y-452267D01*
X-830267Y-451800D01*
X-830767Y-451100D01*
X-831100Y-450283D01*
X-831267Y-449350D01*
Y-448533D01*
X-831100Y-447833D01*
X-830767Y-447017D01*
X-830267Y-446317D01*
X-829767Y-445850D01*
X-829100Y-445500D01*
X-828517D01*
X-827850Y-445733D01*
X-827350Y-446200D01*
G01X-824217Y-452500D02*
Y-445500D01*
X-820383Y-452500D01*
Y-445500D01*
G01X-813833Y-452500D02*
X-817167D01*
Y-445500D01*
X-813833D01*
G01X-815167Y-448883D02*
X-817167D01*
G01X-810367Y-452500D02*
Y-445500D01*
X-808283D01*
X-807617Y-445850D01*
X-807200Y-446317D01*
X-807033Y-447250D01*
X-807200Y-448183D01*
X-807700Y-448767D01*
X-808283Y-449117D01*
X-810367D01*
G01X-808283D02*
X-807033Y-452500D01*
G01X-642033Y-455000D02*
Y-448000D01*
X-640367D01*
X-639700Y-448350D01*
X-639200Y-448817D01*
X-638783Y-449517D01*
X-638450Y-450333D01*
X-638367Y-451500D01*
X-638450Y-452667D01*
X-638783Y-453483D01*
X-639200Y-454184D01*
X-639700Y-454650D01*
X-640367Y-455000D01*
X-642033D01*
G01X-635483D02*
X-633400Y-448000D01*
X-631317Y-455000D01*
G01X-632067Y-452550D02*
X-634733D01*
G01X-626600Y-448000D02*
Y-455000D01*
G01X-628517Y-448000D02*
X-624683D01*
G01X-618133Y-455000D02*
X-621467D01*
Y-448000D01*
X-618133D01*
G01X-619467Y-451383D02*
X-621467D01*
G54D16*
G01X-1184000Y-502500D02*
Y-512500D01*
G01X-1186683Y-502500D02*
X-1181317D01*
G01X-1176833Y-512500D02*
Y-502500D01*
X-1173917D01*
X-1172983Y-503000D01*
X-1172400Y-503667D01*
X-1172167Y-505000D01*
X-1172400Y-506333D01*
X-1173100Y-507167D01*
X-1173917Y-507667D01*
X-1176833D01*
G01X-1173917D02*
X-1172167Y-512500D01*
G01X-1167917D02*
X-1165000Y-502500D01*
X-1162083Y-512500D01*
G01X-1163133Y-509000D02*
X-1166867D01*
G01X-1155500Y-512500D02*
Y-508000D01*
X-1157833Y-502500D01*
G01X-1153167D02*
X-1155500Y-508000D01*
G01X-1135567Y-507167D02*
X-1135100Y-506667D01*
X-1134750Y-505834D01*
X-1134517Y-504667D01*
X-1134750Y-503667D01*
X-1135217Y-503000D01*
X-1136033Y-502500D01*
X-1139183D01*
Y-512500D01*
X-1135333D01*
X-1134517Y-511833D01*
X-1134050Y-510833D01*
X-1133817Y-509667D01*
X-1134050Y-508500D01*
X-1134750Y-507500D01*
X-1135567Y-507167D01*
X-1139183D01*
G01X-1129917Y-512500D02*
X-1127000Y-502500D01*
X-1124083Y-512500D01*
G01X-1125133Y-509000D02*
X-1128867D01*
G01X-1114933Y-503333D02*
X-1115633Y-502833D01*
X-1116450Y-502500D01*
X-1117383D01*
X-1118433Y-503000D01*
X-1119250Y-503833D01*
X-1119833Y-504833D01*
X-1120300Y-506500D01*
X-1120417Y-508000D01*
X-1120183Y-509500D01*
X-1119833Y-510500D01*
X-1119133Y-511500D01*
X-1118317Y-512167D01*
X-1117500Y-512500D01*
X-1116683D01*
X-1115867Y-512167D01*
X-1115167Y-511667D01*
X-1114583Y-511000D01*
G01X-1110567Y-512500D02*
Y-502500D01*
G01X-1106133D02*
X-1110567Y-508667D01*
G01X-1105433Y-512500D02*
X-1108583Y-505834D01*
G01X-1100833Y-512500D02*
Y-502500D01*
X-1098033D01*
X-1097100Y-503000D01*
X-1096400Y-504167D01*
X-1096167Y-505500D01*
X-1096400Y-506833D01*
X-1096983Y-507833D01*
X-1098033Y-508334D01*
X-1100833D01*
G01X-1091333Y-502500D02*
Y-512500D01*
X-1086667D01*
G01X-1082417D02*
X-1079500Y-502500D01*
X-1076583Y-512500D01*
G01X-1077633Y-509000D02*
X-1081367D01*
G01X-1072683Y-512500D02*
Y-502500D01*
X-1067317Y-512500D01*
Y-502500D01*
G01X-1058167Y-512500D02*
X-1062833D01*
Y-502500D01*
X-1058167D01*
G01X-1060033Y-507333D02*
X-1062833D01*
G01X-1043717Y-512500D02*
Y-502500D01*
X-1039283D01*
G01X-1040917Y-507333D02*
X-1043717D01*
G01X-1034917Y-512500D02*
X-1032000Y-502500D01*
X-1029083Y-512500D01*
G01X-1030133Y-509000D02*
X-1033867D01*
G01X-1021567Y-507167D02*
X-1021100Y-506667D01*
X-1020750Y-505834D01*
X-1020517Y-504667D01*
X-1020750Y-503667D01*
X-1021217Y-503000D01*
X-1022033Y-502500D01*
X-1025183D01*
Y-512500D01*
X-1021333D01*
X-1020517Y-511833D01*
X-1020050Y-510833D01*
X-1019817Y-509667D01*
X-1020050Y-508500D01*
X-1020750Y-507500D01*
X-1021567Y-507167D01*
X-1025183D01*
G01X-1002567D02*
X-1002100Y-506667D01*
X-1001750Y-505834D01*
X-1001517Y-504667D01*
X-1001750Y-503667D01*
X-1002217Y-503000D01*
X-1003033Y-502500D01*
X-1006183D01*
Y-512500D01*
X-1002333D01*
X-1001517Y-511833D01*
X-1001050Y-510833D01*
X-1000817Y-509667D01*
X-1001050Y-508500D01*
X-1001750Y-507500D01*
X-1002567Y-507167D01*
X-1006183D01*
G01X-985083Y-515833D02*
X-986250Y-514167D01*
X-986833Y-512500D01*
Y-505834D01*
X-986250Y-504167D01*
X-985083Y-502500D01*
G01X-975000Y-512500D02*
X-975933Y-512333D01*
X-976750Y-511667D01*
X-977450Y-510667D01*
X-977917Y-509500D01*
X-978150Y-508167D01*
Y-506833D01*
X-977917Y-505500D01*
X-977450Y-504333D01*
X-976750Y-503333D01*
X-975933Y-502667D01*
X-975000Y-502500D01*
X-974067Y-502667D01*
X-973250Y-503333D01*
X-972550Y-504333D01*
X-972083Y-505500D01*
X-971850Y-506833D01*
Y-508167D01*
X-972083Y-509500D01*
X-972550Y-510667D01*
X-973250Y-511667D01*
X-974067Y-512333D01*
X-975000Y-512500D01*
G01X-967950Y-511167D02*
X-967017Y-512000D01*
X-965967Y-512500D01*
X-965033D01*
X-964100Y-512000D01*
X-963400Y-511167D01*
X-963050Y-510000D01*
X-963283Y-508834D01*
X-963867Y-507833D01*
X-964917Y-507167D01*
X-966317Y-506833D01*
X-967133Y-506167D01*
X-967483Y-505000D01*
X-967250Y-503833D01*
X-966667Y-503000D01*
X-965850Y-502500D01*
X-965033D01*
X-964217Y-502833D01*
X-963517Y-503667D01*
G01X-958333Y-512500D02*
Y-502500D01*
X-955533D01*
X-954600Y-503000D01*
X-953900Y-504167D01*
X-953667Y-505500D01*
X-953900Y-506833D01*
X-954483Y-507833D01*
X-955533Y-508334D01*
X-958333D01*
G01X-945917Y-515833D02*
X-944750Y-514167D01*
X-944167Y-512500D01*
Y-505834D01*
X-944750Y-504167D01*
X-945917Y-502500D01*
G01X-902000Y-470000D02*
Y-460000D01*
X-903400Y-462000D01*
G01Y-470000D02*
X-900600D01*
G01X-892500Y-470333D02*
X-892733Y-470167D01*
Y-469833D01*
X-892500Y-469667D01*
X-892267Y-469833D01*
Y-470167D01*
X-892500Y-470333D01*
G01Y-465834D02*
X-892733Y-465667D01*
Y-465333D01*
X-892500Y-465167D01*
X-892267Y-465333D01*
Y-465667D01*
X-892500Y-465834D01*
G01X-883000Y-470000D02*
Y-460000D01*
X-884400Y-462000D01*
G01Y-470000D02*
X-881600D01*
G01X-785060Y-472187D02*
X-784127Y-473020D01*
X-783077Y-473520D01*
X-782143D01*
X-781210Y-473020D01*
X-780510Y-472187D01*
X-780160Y-471020D01*
X-780393Y-469854D01*
X-780977Y-468853D01*
X-782027Y-468187D01*
X-783427Y-467853D01*
X-784243Y-467187D01*
X-784593Y-466020D01*
X-784360Y-464853D01*
X-783777Y-464020D01*
X-782960Y-463520D01*
X-782143D01*
X-781327Y-463853D01*
X-780627Y-464687D01*
G01X-775560Y-473520D02*
Y-463520D01*
G01X-770660D02*
Y-473520D01*
G01Y-468520D02*
X-775560D01*
G01X-766527Y-473520D02*
X-763610Y-463520D01*
X-760693Y-473520D01*
G01X-761743Y-470020D02*
X-765477D01*
G01X-757610Y-463520D02*
X-755977Y-473520D01*
X-754110Y-463520D01*
X-752243Y-473520D01*
X-750610Y-463520D01*
G01X-668067Y-470500D02*
X-667367Y-471667D01*
X-666433Y-472333D01*
X-665383Y-472500D01*
X-664450Y-472333D01*
X-663517Y-471500D01*
X-662933Y-470500D01*
X-662817Y-469500D01*
X-663050Y-468334D01*
X-663867Y-467500D01*
X-664683Y-467167D01*
X-665733D01*
G01X-664683D02*
X-663983Y-466667D01*
X-663400Y-465834D01*
X-663167Y-464833D01*
X-663400Y-463833D01*
X-663983Y-463000D01*
X-665033Y-462500D01*
X-666083Y-462667D01*
X-667133Y-463333D01*
G01X-656000Y-462500D02*
X-656933Y-462833D01*
X-657633Y-463667D01*
X-658100Y-464667D01*
X-658450Y-466000D01*
X-658567Y-467500D01*
X-658450Y-469000D01*
X-658100Y-470333D01*
X-657633Y-471334D01*
X-656933Y-472167D01*
X-656000Y-472500D01*
X-655067Y-472167D01*
X-654367Y-471334D01*
X-653900Y-470333D01*
X-653550Y-469000D01*
X-653433Y-467500D01*
X-653550Y-466000D01*
X-653900Y-464667D01*
X-654367Y-463667D01*
X-655067Y-462833D01*
X-656000Y-462500D01*
G01X-648017Y-469167D02*
X-644983D01*
G01X-639917Y-472500D02*
X-637000Y-462500D01*
X-634083Y-472500D01*
G01X-635133Y-469000D02*
X-638867D01*
G01X-629833Y-472500D02*
Y-462500D01*
X-627033D01*
X-626100Y-463000D01*
X-625400Y-464167D01*
X-625167Y-465500D01*
X-625400Y-466833D01*
X-625983Y-467833D01*
X-627033Y-468334D01*
X-629833D01*
G01X-620333Y-472500D02*
Y-462500D01*
X-617417D01*
X-616483Y-463000D01*
X-615900Y-463667D01*
X-615667Y-465000D01*
X-615900Y-466333D01*
X-616600Y-467167D01*
X-617417Y-467667D01*
X-620333D01*
G01X-617417D02*
X-615667Y-472500D01*
G01X-610017Y-469167D02*
X-606983D01*
G01X-599000Y-472500D02*
Y-462500D01*
X-600400Y-464500D01*
G01Y-472500D02*
X-597600D01*
G01X-588100D02*
Y-462500D01*
X-592417Y-469667D01*
X-586583D01*
G54D26*
G01X-1020800Y-457700D02*
G02X-1020300Y-458200I0J-500D01*
G01Y-458400D01*
G02X-1020900Y-459000I-600J0D01*
G01X-1021300D01*
G01X-1021800Y-460500D02*
Y-457700D01*
X-1020600D01*
G01X-1018340Y-459100D02*
G03I-2660J0D01*
G01X-1020700D02*
X-1020200Y-460500D01*
G54D17*
G01X-1246390Y-153490D02*
X-1246200Y-153300D01*
Y-126300D01*
X-1216500Y-96600D01*
X-1197100D01*
X-1188500Y-105200D01*
X-1173800D01*
X-1131700Y-63100D01*
X-1107700D01*
G01X-1241142Y-178998D02*
X-1241030Y-178887D01*
Y-177030D01*
X-1239700Y-175700D01*
Y-129330D01*
X-1216970Y-106600D01*
X-1204700D01*
X-1199300Y-112000D01*
X-1167400D01*
X-1128800Y-73400D01*
X-1107700D01*
G01X-1244291Y-177998D02*
Y-172691D01*
X-1243000Y-171400D01*
Y-127990D01*
X-1215010Y-100000D01*
X-1200300D01*
X-1191800Y-108500D01*
X-1170400D01*
X-1130100Y-68200D01*
X-1107800D01*
G01X-1114500Y-129000D02*
X-1118270Y-132770D01*
X-1127440D01*
X-1130870Y-136200D01*
Y-141720D01*
X-1137410Y-148260D01*
Y-153930D01*
X-1126460Y-164880D01*
X-1119110D01*
X-1114979Y-169011D01*
Y-170700D01*
G01X-1106979D02*
Y-167709D01*
X-1097130Y-157860D01*
X-1093760D01*
X-1088780Y-152880D01*
Y-140770D01*
X-1096260Y-133290D01*
X-1106210D01*
X-1110500Y-129000D01*
G01X-244300Y-129300D02*
X-247770Y-132770D01*
X-257361D01*
X-260791Y-136200D01*
Y-141720D01*
X-267331Y-148260D01*
Y-153930D01*
X-256381Y-164880D01*
X-249031D01*
X-244900Y-169011D01*
Y-170700D01*
G01X-240300Y-129300D02*
X-236310Y-133290D01*
X-226181D01*
X-218701Y-140770D01*
Y-152880D01*
X-223681Y-157860D01*
X-227051D01*
X-236900Y-167709D01*
Y-170700D01*
G54D27*
G01X-1245710Y-189905D02*
X-1245034Y-189229D01*
G02X-1244288Y-188920I747J-747D01*
G01X-1243473D01*
G02X-1241555Y-189715I0J-2713D01*
G03X-1238451Y-191000I3103J3103D01*
G01X-1217693D01*
G03X-1214275Y-189585I0J4833D01*
G01X-1209441Y-184751D01*
G02X-1207388Y-183900I2054J-2054D01*
G01X-1163279D01*
G03X-1160929Y-181550I0J2350D01*
G01Y-172671D01*
G03X-1163500Y-170100I-2571J0D01*
G02X-1165512Y-168088I0J2012D01*
G01Y-167953D01*
G01X-1245710Y-186705D02*
X-1245549Y-186866D01*
G03X-1243850Y-187570I1699J1699D01*
G01X-1243473D01*
G02X-1240600Y-188760I0J-4063D01*
G03X-1238451Y-189650I2149J2149D01*
G01X-1236034D01*
X-1235354Y-188970D01*
X-1234174D01*
X-1233494Y-189650D01*
X-1228568D01*
X-1227668Y-188750D01*
X-1226028D01*
X-1225128Y-189650D01*
X-1223488D01*
X-1222588Y-188750D01*
X-1220948D01*
X-1220048Y-189650D01*
X-1217692D01*
G03X-1215230Y-188630I0J3482D01*
G01X-1212509Y-185909D01*
X-1210396Y-183796D01*
G02X-1207388Y-182550I3008J-3008D01*
G01X-1206437D01*
X-1205527Y-181640D01*
X-1204007D01*
X-1203097Y-182550D01*
X-1201457D01*
X-1200547Y-181640D01*
X-1199027D01*
X-1198117Y-182550D01*
X-1196477D01*
X-1195567Y-181640D01*
X-1194047D01*
X-1193137Y-182550D01*
X-1185457D01*
X-1184557Y-181650D01*
X-1182917D01*
X-1182017Y-182550D01*
X-1180377D01*
X-1179477Y-181650D01*
X-1177837D01*
X-1176937Y-182550D01*
X-1170918D01*
X-1170018Y-181650D01*
X-1168358D01*
X-1167458Y-182550D01*
X-1163279D01*
G03X-1162279Y-181550I0J1000D01*
G01Y-172671D01*
G03X-1163500Y-171450I-1221J0D01*
G03X-1165512Y-173462I0J-2012D01*
G01Y-173465D01*
G01X-1232340Y-185380D02*
X-1232621Y-185099D01*
G02X-1233250Y-183580I1519J1519D01*
G02X-1232047Y-180677I4106J0D01*
G01X-1230649Y-179278D01*
G03X-1229443Y-176367I-2911J2911D01*
G01Y-173993D01*
G02X-1228300Y-172850I1143J0D01*
G01X-1227460D01*
X-1226610Y-173700D01*
X-1225170D01*
X-1224320Y-172850D01*
X-1222680D01*
X-1221930Y-173600D01*
X-1220290D01*
X-1219540Y-172850D01*
X-1218050D01*
G03X-1213900Y-168700I0J4150D01*
G01X-1213890Y-168690D01*
Y-165659D01*
X-1213900Y-165649D01*
Y-163511D01*
X-1213240Y-162851D01*
Y-161551D01*
X-1213900Y-160891D01*
Y-159981D01*
X-1212999Y-159080D01*
Y-157920D01*
X-1213900Y-157019D01*
Y-155781D01*
X-1212999Y-154880D01*
Y-153601D01*
X-1213900Y-152700D01*
Y-151436D01*
G02X-1213450Y-150350I1536J0D01*
G01X-1213087Y-149987D01*
G02X-1210100Y-148750I2987J-2987D01*
G03X-1205429Y-144079I0J4671D01*
G01Y-141464D01*
X-1204679Y-140714D01*
Y-139074D01*
X-1205429Y-138324D01*
Y-136684D01*
X-1204519Y-135774D01*
Y-134454D01*
X-1205429Y-133544D01*
Y-132704D01*
G02X-1204294Y-129966I3873J0D01*
G01X-1203529Y-129200D01*
X-1201869Y-127540D01*
G02X-1199479Y-126550I2390J-2390D01*
G01X-1193947D01*
X-1193037Y-127460D01*
X-1190817D01*
X-1189907Y-126550D01*
X-1188267D01*
X-1187357Y-127460D01*
X-1185137D01*
X-1184227Y-126550D01*
X-1181100D01*
G02X-1177950Y-129700I0J-3150D01*
G01Y-169200D01*
G02X-1178800Y-170050I-850J0D01*
G01X-1179300D01*
G02X-1181260Y-168090I0J1960D01*
G01Y-167953D01*
G01X-1235540Y-185380D02*
X-1235208Y-185048D01*
G03X-1234600Y-183580I-1468J1468D01*
G02X-1233002Y-179722I5456J0D01*
G01X-1231604Y-178324D01*
G03X-1230793Y-176367I-1957J1957D01*
G01Y-173993D01*
G02X-1228300Y-171500I2493J0D01*
G01X-1218050D01*
G03X-1215250Y-168700I0J2800D01*
G01Y-151436D01*
G02X-1214405Y-149395I2886J0D01*
G01X-1214042Y-149033D01*
G02X-1210100Y-147400I3942J-3942D01*
G03X-1206779Y-144079I0J3321D01*
G01Y-132704D01*
G02X-1205249Y-129011I5223J0D01*
G01X-1204483Y-128245D01*
X-1202823Y-126585D01*
G02X-1199479Y-125200I3345J-3345D01*
G01X-1181100D01*
G02X-1176600Y-129700I0J-4500D01*
G01Y-169200D01*
G02X-1178800Y-171400I-2200J0D01*
G01X-1179300D01*
G03X-1181260Y-173360I0J-1960D01*
G01Y-173465D01*
G01X-1157638Y-178583D02*
X-1155557Y-176502D01*
X-1155117D01*
G03X-1151600Y-172985I0J3517D01*
G01Y-135672D01*
G03X-1153496Y-131095I-6473J0D01*
G01X-1164050Y-120540D01*
G03X-1167166Y-119250I-3115J-3115D01*
G01X-1218020D01*
G03X-1224490Y-121930I0J-9150D01*
G01X-1229820Y-127260D01*
X-1231744Y-129184D01*
G03X-1232368Y-130690I1506J-1506D01*
G01Y-132117D01*
G02X-1233293Y-134350I-3158J0D01*
G01X-1157638Y-173071D02*
X-1155557Y-175152D01*
X-1155117D01*
G03X-1152950Y-172985I0J2167D01*
G01Y-171852D01*
X-1153860Y-170942D01*
Y-168910D01*
X-1152950Y-168000D01*
Y-165165D01*
X-1153860Y-164255D01*
Y-162360D01*
X-1152950Y-161450D01*
Y-155207D01*
X-1153860Y-154297D01*
Y-152577D01*
X-1152950Y-151667D01*
Y-150027D01*
X-1153860Y-149117D01*
Y-147397D01*
X-1152950Y-146487D01*
Y-135672D01*
G03X-1154451Y-132049I-5123J0D01*
G01X-1165005Y-121495D01*
G03X-1167166Y-120600I-2161J-2161D01*
G01X-1172000D01*
X-1172910Y-121510D01*
X-1174969D01*
X-1175879Y-120600D01*
X-1193000D01*
X-1193910Y-121510D01*
X-1196113D01*
X-1197023Y-120600D01*
X-1205459D01*
X-1206359Y-121500D01*
X-1207999D01*
X-1208899Y-120600D01*
X-1212712D01*
X-1213612Y-121500D01*
X-1215252D01*
X-1216152Y-120600D01*
X-1218020D01*
G03X-1223535Y-122885I0J-7800D01*
G01X-1226008Y-125357D01*
Y-125672D01*
Y-125958D01*
X-1227197Y-127147D01*
X-1227798D01*
X-1230790Y-130139D01*
G03X-1231018Y-130690I551J-551D01*
G01Y-132117D01*
G03X-1230093Y-134350I3158J0D01*
G01X-1209420Y-167360D02*
G03X-1208440Y-164994I-2366J2366D01*
G01Y-164790D01*
G02X-1206594Y-160334I6301J0D01*
G01X-1202641Y-156381D01*
G03X-1201829Y-154420I-1961J1961D01*
G01Y-153580D01*
X-1202739Y-152670D01*
Y-151050D01*
X-1201829Y-150140D01*
Y-148542D01*
X-1202720Y-147650D01*
Y-146273D01*
X-1201829Y-145382D01*
Y-140200D01*
G02X-1198679Y-137050I3150J0D01*
G03X-1197008Y-135379I0J1671D01*
G01Y-134882D01*
G01X-1206220Y-167360D02*
G02X-1207090Y-165260I2100J2100D01*
G01Y-164790D01*
G02X-1205640Y-161289I4951J0D01*
G01X-1201686Y-157336D01*
G03X-1200479Y-154420I-2916J2916D01*
G01Y-140200D01*
G02X-1198679Y-138400I1800J0D01*
G02X-1197008Y-140071I0J-1671D01*
G01Y-140394D01*
G01X-1014488Y-167953D02*
Y-167988D01*
G02X-1016500Y-170000I-2012J0D01*
G01X-1019780D01*
X-1019940Y-169840D01*
X-1021720D01*
X-1021880Y-170000D01*
X-1024500D01*
G02X-1029500Y-165000I0J5000D01*
G01Y-163210D01*
G02X-1029160Y-162870I340J0D01*
G03X-1028590Y-162300I0J570D01*
G01Y-161270D01*
G03X-1029190Y-160670I-600J0D01*
G02X-1029500Y-160360I0J310D01*
G01Y-155050D01*
G02X-1029120Y-154670I380J0D01*
G03X-1028590Y-154140I0J530D01*
G01Y-152480D01*
G03X-1029140Y-151930I-550J0D01*
G02X-1029500Y-151570I0J360D01*
G01Y-147040D01*
G02X-1029140Y-146680I360J0D01*
G03X-1028590Y-146130I0J550D01*
G01Y-144470D01*
G03X-1029180Y-143880I-590J0D01*
G02X-1029500Y-143560I0J320D01*
G01Y-140440D01*
G02X-1029210Y-140150I290J0D01*
G03X-1028590Y-139530I0J620D01*
G01Y-138330D01*
G03X-1029250Y-137670I-660J0D01*
G02X-1029500Y-137420I0J250D01*
G01Y-73864D01*
G02X-1025000Y-63000I15364J0D01*
G01X-1022036Y-60036D01*
G03X-1018500Y-51500I-8536J8536D01*
G01Y-51060D01*
G02X-1016917Y-47238I5405J0D01*
G01X-1015779Y-46100D01*
X-1015749Y-46070D01*
G02X-1011959Y-44500I3790J-3790D01*
G02X-1009533Y-45505I0J-3430D01*
G01X-1008613Y-46425D01*
G02Y-48165I-870J-870D01*
G01X-1010459Y-50011D01*
G02X-1010562Y-50088I-311J311D01*
G01X-1010650Y-50135D01*
X-1010659Y-50140D01*
G02X-1011255Y-49960I-208J388D01*
G01X-1012205Y-48187D01*
G01X-1014488Y-173465D02*
Y-173362D01*
G03X-1016500Y-171350I-2012J0D01*
G01X-1024500D01*
G02X-1030850Y-165000I0J6350D01*
G01Y-73864D01*
G02X-1025955Y-62045I16714J0D01*
G01X-1022990Y-59081D01*
G03X-1019850Y-51500I-7581J7581D01*
G01Y-51060D01*
G02X-1017872Y-46284I6755J0D01*
G01X-1016703Y-45115D01*
G02X-1011959Y-43150I4745J-4744D01*
G02X-1008579Y-44550I0J-4780D01*
G01X-1007659Y-45470D01*
G02Y-49120I-1825J-1825D01*
G01X-1009504Y-50965D01*
G02X-1009925Y-51278I-1266J1266D01*
G01X-1010022Y-51330D01*
G03X-1010202Y-51925I208J-388D01*
G01X-1009252Y-53698D01*
G01Y-68659D02*
X-1010202Y-66886D01*
G02X-1010022Y-66290I388J208D01*
G01X-1009867Y-66207D01*
G03X-1009447Y-65895I-845J1578D01*
G01X-1009219Y-65668D01*
G03X-1007700Y-62000I-3668J3668D01*
G01Y-61100D01*
G03X-1008336Y-59564I-2173J0D01*
G01X-1008625Y-59275D01*
G03X-1010858Y-58350I-2233J-2233D01*
G01X-1014538D01*
G03X-1018079Y-61891I0J-3541D01*
G01Y-62331D01*
G02X-1018333Y-62945I-869J0D01*
G03X-1026329Y-82248I19303J-19303D01*
G01Y-129095D01*
G03X-1023179Y-136700I10755J0D01*
G03X-1019075Y-138400I4104J4104D01*
G01X-1017479D01*
G02X-1015777Y-139105I0J-2407D01*
G01X-1014488Y-140394D01*
G01X-1012205Y-78108D02*
X-1011255Y-79881D01*
G02X-1011435Y-80476I-388J-208D01*
G01X-1013274Y-82315D01*
G02X-1015410Y-83200I-2136J2136D01*
G01X-1016949D01*
G03X-1020279Y-86530I0J-3330D01*
G01Y-91197D01*
Y-91200D01*
Y-108250D01*
G03X-1017952Y-113867I7944J0D01*
G01X-1015915Y-115905D01*
X-1013036Y-118783D01*
G02X-1011279Y-123026I-4243J-4243D01*
G01Y-129571D01*
Y-152700D01*
G02X-1012079Y-153500I-800J0D01*
G01X-1012406D01*
G02X-1014488Y-151417I0J2083D01*
G01X-1009252Y-83620D02*
X-1010202Y-81847D01*
G03X-1010797Y-81666I-388J-208D01*
G01X-1010757Y-81707D01*
X-1012319Y-83270D01*
G02X-1015410Y-84550I-3091J3091D01*
G01X-1016949D01*
G03X-1018929Y-86530I0J-1980D01*
G01Y-91194D01*
Y-91197D01*
Y-108250D01*
G03X-1016997Y-112913I6594J0D01*
G01X-1014960Y-114950D01*
X-1012082Y-117828D01*
G02X-1009929Y-123026I-5198J-5198D01*
G01Y-125561D01*
X-1009750Y-125740D01*
Y-127532D01*
X-1009929Y-127711D01*
Y-129581D01*
G03X-1009540Y-129970I389J0D01*
G02X-1009019Y-130491I0J-521D01*
G01Y-131919D01*
G02X-1009620Y-132520I-601J0D01*
G03X-1009929Y-132829I0J-309D01*
G01Y-152700D01*
G02X-1012079Y-154850I-2150J0D01*
G01X-1012604D01*
G03X-1013500Y-155221I0J-1267D01*
G01X-1013979Y-155701D01*
G03X-1014488Y-156929I1229J-1229D01*
G01X-1012205Y-63147D02*
X-1011255Y-64920D01*
G03X-1010659Y-65100I388J208D01*
G01X-1010505Y-65017D01*
G03X-1010401Y-64941I-208J388D01*
G01X-1010174Y-64713D01*
G03X-1009050Y-62000I-2713J2713D01*
G01Y-61100D01*
G03X-1009291Y-60518I-823J0D01*
G01X-1009580Y-60230D01*
G03X-1010858Y-59700I-1279J-1279D01*
G01X-1014538D01*
G03X-1016729Y-61891I0J-2191D01*
G01Y-62331D01*
G02X-1017379Y-63900I-2219J0D01*
G03X-1024979Y-82248I18348J-18348D01*
G01Y-95546D01*
X-1024069Y-96456D01*
Y-97696D01*
X-1024979Y-98606D01*
Y-103161D01*
G03X-1024660Y-103480I319J0D01*
G02X-1024140Y-104000I0J-520D01*
G01Y-105760D01*
G02X-1024640Y-106260I-500J0D01*
G03X-1024979Y-106599I0J-339D01*
G01Y-109460D01*
G03X-1024539Y-109900I440J0D01*
G01X-1024530D01*
G02X-1024070Y-110360I0J-460D01*
G01Y-112560D01*
G02X-1024570Y-113060I-500J0D01*
G03X-1024979Y-113469I0J-409D01*
G01Y-116971D01*
G03X-1024630Y-117320I349J0D01*
G02X-1024070Y-117880I0J-560D01*
G01Y-119520D01*
G02X-1024650Y-120100I-580J0D01*
G01X-1024700D01*
G03X-1024979Y-120379I0J-279D01*
G01Y-129095D01*
G03X-1022224Y-135745I9405J0D01*
G03X-1019075Y-137050I3150J3150D01*
G01X-1017479D01*
G03X-1016075Y-136468I0J1986D01*
G01X-1014488Y-134882D01*
G01X-1006614Y-140000D02*
Y-140165D01*
G03X-1004679Y-142100I1935J0D01*
G01X-1004129D01*
G03X-1003429Y-141400I0J700D01*
G01Y-116266D01*
G03X-1004055Y-114755I-2137J0D01*
G01X-1009149Y-109660D01*
G02X-1010479Y-106450I3210J3210D01*
G01Y-105900D01*
G03X-1011427Y-103611I-3237J0D01*
G01X-1012283Y-102755D01*
G02X-1013879Y-98903I3852J3852D01*
G01Y-98800D01*
G02X-1013105Y-96933I2640J0D01*
G01X-1011998Y-95826D01*
G02X-1011578Y-95514I1266J-1266D01*
G01X-1011435Y-95437D01*
G03X-1011255Y-94841I-208J388D01*
G01X-1012205Y-93068D01*
G01X-1006614Y-145512D02*
Y-145385D01*
G02X-1004679Y-143450I1935J0D01*
G01X-1004129D01*
G03X-1002079Y-141400I0J2050D01*
G01Y-126039D01*
G02X-1001690Y-125650I389J0D01*
G03X-1001169Y-125129I0J521D01*
G01Y-123461D01*
G03X-1001770Y-122860I-601J0D01*
G02X-1002079Y-122551I0J309D01*
G01Y-120314D01*
X-1001910Y-120145D01*
Y-118309D01*
X-1002079Y-118140D01*
Y-116266D01*
G03X-1003100Y-113800I-3487J0D01*
G01X-1008194Y-108706D01*
G02X-1009129Y-106450I2256J2256D01*
G01Y-105900D01*
G03X-1010472Y-102657I-4587J0D01*
G01X-1011329Y-101800D01*
G02X-1012529Y-98903I2897J2897D01*
G01Y-98800D01*
G02X-1012151Y-97888I1290J0D01*
G01X-1011043Y-96780D01*
G02X-1010940Y-96703I311J-311D01*
G01X-1010797Y-96627D01*
G02X-1010202Y-96807I208J-388D01*
G01X-1009252Y-98580D01*
G01X-998740Y-151417D02*
G03X-996657Y-153500I2083J0D01*
G01X-996579D01*
G03X-995579Y-152500I0J1000D01*
G01Y-122444D01*
G03X-1001479Y-108200I-20144J0D01*
G02X-1004879Y-99992I8208J8208D01*
G01Y-99300D01*
G02X-1003648Y-96328I4203J0D01*
G01X-1003152Y-95832D01*
G02X-1002731Y-95520I1266J-1266D01*
G01X-1002577Y-95437D01*
G03X-1002397Y-94841I-208J388D01*
G01X-1003346Y-93068D01*
G01X-998740Y-156929D02*
G02X-996661Y-154850I2079J0D01*
G01X-996579D01*
G03X-994229Y-152500I0J2350D01*
G01Y-132379D01*
G02X-993890Y-132040I339J0D01*
G03X-993320Y-131470I0J570D01*
G01Y-129930D01*
G03X-993850Y-129400I-530J0D01*
G02X-994229Y-129021I0J379D01*
G01Y-127392D01*
X-994100Y-127263D01*
Y-125559D01*
X-994229Y-125430D01*
Y-122444D01*
G03X-1000524Y-107245I-21494J0D01*
G02X-1003529Y-99992I7254J7254D01*
G01Y-99300D01*
G02X-1002693Y-97283I2853J0D01*
G01X-1002197Y-96787D01*
G02X-1002094Y-96710I311J-311D01*
G01X-1001939Y-96627D01*
G02X-1001344Y-96807I208J-388D01*
G01X-1000394Y-98580D01*
G01X-965945Y-68659D02*
X-966895Y-66886D01*
G03X-967490Y-66706I-388J-208D01*
G01X-967690Y-66813D01*
G03X-967814Y-66954I3189J-2926D01*
G01X-968883Y-68023D01*
G03X-969429Y-69340I1317J-1317D01*
G03X-966809Y-71960I2620J0D01*
G01X-946720D01*
G02X-943600Y-75080I0J-3120D01*
G01Y-154885D01*
G02X-948929Y-167750I-18193J0D01*
G01X-950533Y-169354D01*
Y-170583D01*
X-951633Y-171683D01*
X-952861D01*
X-953983Y-172804D01*
G03Y-173427I311J-311D01*
G01X-953966Y-173444D01*
G02Y-174066I-311J-311D01*
G01X-955580Y-175680D01*
G02X-956100I-260J260D01*
G01X-956168Y-175612D01*
G03X-956791I-311J-311D01*
G01X-959003Y-177824D01*
G03Y-178447I311J-311D01*
G01X-958970Y-178480D01*
G02Y-179070I-295J-295D01*
G01X-960660Y-180760D01*
G02X-961130I-235J235D01*
G01X-961223Y-180667D01*
G03X-961846I-311J-311D01*
G01X-962286Y-181108D01*
G02X-969028Y-183900I-6742J6742D01*
G01X-977229D01*
G02X-979729Y-181400I0J2500D01*
G01Y-172500D01*
G03X-980879Y-171350I-1150J0D01*
G03X-982992Y-173463I0J-2113D01*
G01Y-173465D01*
G01X-968898Y-63147D02*
X-967948Y-64920D01*
G02X-968128Y-65516I-388J-208D01*
G01X-968516Y-65724D01*
G03X-968685Y-65900I4015J-4015D01*
G03X-968808Y-66038I4184J-3838D01*
G01X-969838Y-67069D01*
G03X-970779Y-69340I2271J-2271D01*
G03X-966809Y-73310I3970J0D01*
G01X-946720D01*
G02X-944950Y-75080I0J-1770D01*
G01Y-154885D01*
G02X-949883Y-166795I-16843J0D01*
G01X-963241Y-180153D01*
G02X-969028Y-182550I-5787J5787D01*
G01X-977229D01*
G02X-978379Y-181400I0J1150D01*
G01Y-172500D01*
G03X-980879Y-170000I-2500J0D01*
G01X-980945D01*
G02X-982992Y-167953I0J2047D01*
G01Y-151417D02*
Y-152137D01*
G03X-981579Y-153550I1413J0D01*
G01X-980879D01*
G03X-979729Y-152400I0J1150D01*
G01Y-104210D01*
G02X-978321Y-100812I4805J0D01*
G01X-978042Y-100533D01*
G02X-973979Y-98850I4064J-4064D01*
G01X-973600D01*
G03X-970532Y-97579I0J4339D01*
G01X-968879Y-95926D01*
G02X-968458Y-95614I1266J-1266D01*
G01X-968341Y-95551D01*
X-968128Y-95437D01*
G03X-967948Y-94841I-208J388D01*
G01X-968898Y-93068D01*
G01X-982992Y-156929D02*
Y-156313D01*
G02X-981579Y-154900I1413J0D01*
G01X-980879D01*
G03X-978379Y-152400I0J2500D01*
G01Y-131619D01*
G02X-978000Y-131240I379J0D01*
G03X-977469Y-130709I0J531D01*
G01Y-129411D01*
G03X-977960Y-128920I-491J0D01*
G02X-978379Y-128501I0J419D01*
G01Y-125750D01*
X-978130Y-125501D01*
Y-124115D01*
X-978379Y-123866D01*
Y-104210D01*
G02X-977367Y-101767I3455J0D01*
G01X-977088Y-101488D01*
G02X-973979Y-100200I3109J-3109D01*
G01X-973600D01*
G03X-969577Y-98534I0J5689D01*
G01X-967924Y-96881D01*
G02X-967821Y-96804I311J-311D01*
G01X-967490Y-96627D01*
G02X-966895Y-96807I208J-388D01*
G01X-965945Y-98580D01*
G01X-990866Y-140000D02*
Y-140213D01*
G03X-988979Y-142100I1887J0D01*
G03X-987679Y-140800I0J1300D01*
G01Y-113187D01*
G02X-976933Y-87245I36687J0D01*
G01X-973914Y-84226D01*
G02X-971679Y-83300I2235J-2235D01*
G03X-970745Y-82913I0J1321D01*
G01X-968703Y-80871D01*
G02X-968282Y-80559I1266J-1266D01*
G01X-968128Y-80476D01*
G03X-967948Y-79881I-208J388D01*
G01X-968898Y-78108D01*
G01X-990866Y-145512D02*
Y-145337D01*
G02X-988979Y-143450I1887J0D01*
G03X-986329Y-140800I0J2650D01*
G01Y-127339D01*
G02X-986000Y-127010I329J0D01*
G03X-985319Y-126329I0J681D01*
G01Y-125071D01*
G03X-985950Y-124440I-631J0D01*
G02X-986329Y-124061I0J379D01*
G01Y-121197D01*
X-985930Y-120798D01*
Y-118958D01*
X-986329Y-118560D01*
Y-113187D01*
G02X-975979Y-88200I35337J0D01*
G01X-972959Y-85180D01*
G02X-971679Y-84650I1280J-1280D01*
G03X-969790Y-83868I0J2671D01*
G01X-967748Y-81826D01*
G02X-967645Y-81749I311J-311D01*
G01X-967490Y-81666D01*
G02X-966895Y-81847I208J-388D01*
G01X-965945Y-83620D01*
G01X-960039Y-93068D02*
X-959090Y-94841D01*
G02X-959270Y-95437I-388J-208D01*
G01X-959483Y-95551D01*
X-959600Y-95614D01*
G03X-960021Y-95926I845J-1578D01*
G01X-961673Y-97579D01*
G03X-963879Y-102903I5324J-5324D01*
G01Y-169086D01*
G02X-964879Y-171500I-3414J0D01*
G01X-966375Y-172996D01*
G02X-971579Y-175152I-5204J5204D01*
G01X-973279D01*
G02X-975118Y-173312I0J1839D01*
G01Y-173071D01*
G01Y-178583D02*
Y-178341D01*
G02X-973279Y-176502I1839J0D01*
G01X-971579D01*
G03X-965421Y-173951I0J8709D01*
G01X-963924Y-172455D01*
G03X-962529Y-169086I-3369J3369D01*
G01Y-168050D01*
G02X-962179Y-167700I350J0D01*
G03X-961639Y-167160I0J540D01*
G01Y-165940D01*
G03X-962079Y-165500I-440J0D01*
G01X-962089D01*
G02X-962529Y-165060I0J440D01*
G01Y-161850D01*
G02X-962079Y-161400I450J0D01*
G03X-961639Y-160960I0J440D01*
G01Y-159440D01*
G03X-962179Y-158900I-540J0D01*
G02X-962529Y-158550I0J350D01*
G01Y-155088D01*
X-961779Y-154338D01*
Y-153098D01*
X-962529Y-152348D01*
Y-102903D01*
G02X-960719Y-98534I6180J0D01*
G01X-959066Y-96881D01*
G02X-958963Y-96804I311J-311D01*
G01X-958632Y-96627D01*
G02X-958036Y-96807I208J-388D01*
G01X-957087Y-98580D01*
G01X-375631Y-189905D02*
X-374956Y-189229D01*
G02X-374209Y-188920I747J-747D01*
G01X-373394D01*
G02X-371476Y-189715I0J-2713D01*
G03X-368373Y-191000I3103J3103D01*
G01X-347614D01*
G03X-344197Y-189585I0J4833D01*
G01X-339363Y-184751D01*
G02X-337309Y-183900I2054J-2054D01*
G01X-293200D01*
G03X-290850Y-181550I0J2350D01*
G01Y-172671D01*
G03X-293421Y-170100I-2571J0D01*
G02X-295433Y-168088I0J2012D01*
G01Y-167953D01*
G01X-375631Y-186705D02*
X-375470Y-186866D01*
G03X-373771Y-187570I1699J1699D01*
G01X-373394D01*
G02X-370521Y-188760I0J-4063D01*
G03X-368373Y-189650I2149J2149D01*
G01X-365955D01*
X-365275Y-188970D01*
X-364095D01*
X-363415Y-189650D01*
X-358489D01*
X-357589Y-188750D01*
X-355949D01*
X-355049Y-189650D01*
X-353409D01*
X-352509Y-188750D01*
X-350869D01*
X-349969Y-189650D01*
X-347614D01*
G03X-345151Y-188630I0J3482D01*
G01X-342430Y-185909D01*
X-340317Y-183796D01*
G02X-337309Y-182550I3008J-3008D01*
G01X-336358D01*
X-335448Y-181640D01*
X-333928D01*
X-333018Y-182550D01*
X-331378D01*
X-330468Y-181640D01*
X-328948D01*
X-328038Y-182550D01*
X-326398D01*
X-325488Y-181640D01*
X-323968D01*
X-323058Y-182550D01*
X-315379D01*
X-314479Y-181650D01*
X-312839D01*
X-311939Y-182550D01*
X-310299D01*
X-309399Y-181650D01*
X-307759D01*
X-306859Y-182550D01*
X-300839D01*
X-299939Y-181650D01*
X-298279D01*
X-297379Y-182550D01*
X-293200D01*
G03X-292200Y-181550I0J1000D01*
G01Y-172671D01*
G03X-293421Y-171450I-1221J0D01*
G03X-295433Y-173462I0J-2012D01*
G01Y-173465D01*
G01X-365461Y-185380D02*
X-365129Y-185048D01*
G03X-364521Y-183580I-1468J1468D01*
G02X-362923Y-179722I5456J0D01*
G01X-361525Y-178324D01*
G03X-360714Y-176367I-1957J1957D01*
G01Y-173993D01*
G02X-358221Y-171500I2493J0D01*
G01X-347971D01*
G03X-345171Y-168700I0J2800D01*
G01Y-151436D01*
G02X-344326Y-149395I2886J0D01*
G01X-343963Y-149033D01*
G02X-340021Y-147400I3942J-3942D01*
G03X-336700Y-144079I0J3321D01*
G01Y-132704D01*
G02X-335170Y-129011I5223J0D01*
G01X-334405Y-128245D01*
X-332745Y-126585D01*
G02X-329400Y-125200I3345J-3345D01*
G01X-311021D01*
G02X-306521Y-129700I0J-4500D01*
G01Y-169200D01*
G02X-308721Y-171400I-2200J0D01*
G01X-309221D01*
G03X-311181Y-173360I0J-1960D01*
G01Y-173465D01*
G01X-362261Y-185380D02*
X-362542Y-185099D01*
G02X-363171Y-183580I1519J1519D01*
G02X-361969Y-180677I4106J0D01*
G01X-360570Y-179278D01*
G03X-359364Y-176367I-2911J2911D01*
G01Y-173993D01*
G02X-358221Y-172850I1143J0D01*
G01X-357381D01*
X-356531Y-173700D01*
X-355091D01*
X-354241Y-172850D01*
X-352601D01*
X-351851Y-173600D01*
X-350211D01*
X-349461Y-172850D01*
X-347971D01*
G03X-343821Y-168700I0J4150D01*
G01X-343811Y-168690D01*
Y-165659D01*
X-343821Y-165649D01*
Y-163511D01*
X-343161Y-162851D01*
Y-161551D01*
X-343821Y-160891D01*
Y-159981D01*
X-342920Y-159080D01*
Y-157920D01*
X-343821Y-157019D01*
Y-155781D01*
X-342920Y-154880D01*
Y-153601D01*
X-343821Y-152700D01*
Y-151436D01*
G02X-343371Y-150350I1536J0D01*
G01X-343009Y-149987D01*
G02X-340021Y-148750I2987J-2987D01*
G03X-335350Y-144079I0J4671D01*
G01Y-141464D01*
X-334600Y-140714D01*
Y-139074D01*
X-335350Y-138324D01*
Y-136684D01*
X-334440Y-135774D01*
Y-134454D01*
X-335350Y-133544D01*
Y-132704D01*
G02X-334216Y-129966I3873J0D01*
G01X-333450Y-129200D01*
X-331790Y-127540D01*
G02X-329400Y-126550I2390J-2390D01*
G01X-323868D01*
X-322958Y-127460D01*
X-320738D01*
X-319828Y-126550D01*
X-318188D01*
X-317278Y-127460D01*
X-315058D01*
X-314148Y-126550D01*
X-311021D01*
G02X-307871Y-129700I0J-3150D01*
G01Y-169200D01*
G02X-308721Y-170050I-850J0D01*
G01X-309221D01*
G02X-311181Y-168090I0J1960D01*
G01Y-167953D01*
G01X-287559Y-173071D02*
X-285478Y-175152D01*
X-285038D01*
G03X-282871Y-172985I0J2167D01*
G01Y-171852D01*
X-283781Y-170942D01*
Y-168910D01*
X-282871Y-168000D01*
Y-165165D01*
X-283781Y-164255D01*
Y-162360D01*
X-282871Y-161450D01*
Y-155207D01*
X-283781Y-154297D01*
Y-152577D01*
X-282871Y-151667D01*
Y-150027D01*
X-283781Y-149117D01*
Y-147397D01*
X-282871Y-146487D01*
Y-135672D01*
G03X-284372Y-132049I-5123J0D01*
G01X-294926Y-121495D01*
G03X-297087Y-120600I-2161J-2161D01*
G01X-301921D01*
X-302831Y-121510D01*
X-304891D01*
X-305801Y-120600D01*
X-322921D01*
X-323831Y-121510D01*
X-326035D01*
X-326945Y-120600D01*
X-335380D01*
X-336280Y-121500D01*
X-337920D01*
X-338820Y-120600D01*
X-342633D01*
X-343533Y-121500D01*
X-345173D01*
X-346073Y-120600D01*
X-347941D01*
G03X-353457Y-122885I0J-7800D01*
G01X-355929Y-125357D01*
Y-125672D01*
Y-125958D01*
X-357118Y-127147D01*
X-357719D01*
X-360711Y-130139D01*
G03X-360939Y-130690I551J-551D01*
G01Y-132117D01*
G03X-360014Y-134350I3158J0D01*
G01X-287559Y-178583D02*
X-285478Y-176502D01*
X-285038D01*
G03X-281521Y-172985I0J3517D01*
G01Y-135672D01*
G03X-283417Y-131095I-6473J0D01*
G01X-293972Y-120540D01*
G03X-297087Y-119250I-3115J-3115D01*
G01X-347941D01*
G03X-354411Y-121930I0J-9150D01*
G01X-359741Y-127260D01*
X-361665Y-129184D01*
G03X-362289Y-130690I1506J-1506D01*
G01Y-132117D01*
G02X-363214Y-134350I-3158J0D01*
G01X-339341Y-167360D02*
G03X-338361Y-164994I-2366J2366D01*
G01Y-164790D01*
G02X-336516Y-160334I6301J0D01*
G01X-332562Y-156381D01*
G03X-331750Y-154420I-1961J1961D01*
G01Y-153580D01*
X-332660Y-152670D01*
Y-151050D01*
X-331750Y-150140D01*
Y-148542D01*
X-332641Y-147650D01*
Y-146273D01*
X-331750Y-145382D01*
Y-140200D01*
G02X-328600Y-137050I3150J0D01*
G03X-326929Y-135379I0J1671D01*
G01Y-134882D01*
G01X-336141Y-167360D02*
G02X-337011Y-165260I2100J2100D01*
G01Y-164790D01*
G02X-335561Y-161289I4951J0D01*
G01X-331608Y-157336D01*
G03X-330400Y-154420I-2916J2916D01*
G01Y-140200D01*
G02X-328600Y-138400I1800J0D01*
G02X-326929Y-140071I0J-1671D01*
G01Y-140394D01*
G01X-144409Y-173465D02*
Y-173362D01*
G03X-146421Y-171350I-2012J0D01*
G01X-154421D01*
G02X-160771Y-165000I0J6350D01*
G01Y-73864D01*
G02X-155876Y-62045I16714J0D01*
G01X-152911Y-59081D01*
G03X-149771Y-51500I-7581J7581D01*
G01Y-51060D01*
G02X-147793Y-46284I6755J0D01*
G01X-146625Y-45115D01*
G02X-141880Y-43150I4745J-4744D01*
G02X-138500Y-44550I0J-4780D01*
G01X-137580Y-45470D01*
G02Y-49120I-1825J-1825D01*
G01X-139425Y-50965D01*
G02X-139846Y-51278I-1266J1266D01*
G01X-139943Y-51330D01*
G03X-140123Y-51925I208J-388D01*
G01X-139173Y-53698D01*
G01X-144409Y-167953D02*
Y-167988D01*
G02X-146421Y-170000I-2012J0D01*
G01X-149701D01*
X-149861Y-169840D01*
X-151641D01*
X-151801Y-170000D01*
X-154421D01*
G02X-159421Y-165000I0J5000D01*
G01Y-163210D01*
G02X-159081Y-162870I340J0D01*
G03X-158511Y-162300I0J570D01*
G01Y-161270D01*
G03X-159111Y-160670I-600J0D01*
G02X-159421Y-160360I0J310D01*
G01Y-155050D01*
G02X-159041Y-154670I380J0D01*
G03X-158511Y-154140I0J530D01*
G01Y-152480D01*
G03X-159061Y-151930I-550J0D01*
G02X-159421Y-151570I0J360D01*
G01Y-147040D01*
G02X-159061Y-146680I360J0D01*
G03X-158511Y-146130I0J550D01*
G01Y-144470D01*
G03X-159101Y-143880I-590J0D01*
G02X-159421Y-143560I0J320D01*
G01Y-140440D01*
G02X-159131Y-140150I290J0D01*
G03X-158511Y-139530I0J620D01*
G01Y-138330D01*
G03X-159171Y-137670I-660J0D01*
G02X-159421Y-137420I0J250D01*
G01Y-73864D01*
G02X-154921Y-63000I15364J0D01*
G01X-151957Y-60036D01*
G03X-148421Y-51500I-8536J8536D01*
G01Y-51060D01*
G02X-146838Y-47238I5405J0D01*
G01X-145700Y-46100D01*
X-145670Y-46070D01*
G02X-141880Y-44500I3790J-3790D01*
G02X-139455Y-45505I0J-3430D01*
G01X-138535Y-46425D01*
G02Y-48165I-870J-870D01*
G01X-140380Y-50011D01*
G02X-140483Y-50088I-311J311D01*
G01X-140571Y-50135D01*
X-140581Y-50140D01*
G02X-141176Y-49960I-208J388D01*
G01X-142126Y-48187D01*
G01Y-78108D02*
X-141176Y-79881D01*
G02X-141356Y-80476I-388J-208D01*
G01X-143195Y-82315D01*
G02X-145331Y-83200I-2136J2136D01*
G01X-146870D01*
G03X-150200Y-86530I0J-3330D01*
G01Y-91197D01*
Y-91200D01*
Y-108250D01*
G03X-147873Y-113867I7944J0D01*
G01X-145836Y-115905D01*
X-142958Y-118783D01*
G02X-141200Y-123026I-4243J-4243D01*
G01Y-129571D01*
Y-152700D01*
G02X-142000Y-153500I-800J0D01*
G01X-142327D01*
G02X-144409Y-151417I0J2083D01*
G01X-139173Y-83620D02*
X-140123Y-81847D01*
G03X-140719Y-81666I-388J-208D01*
G01X-140678Y-81707D01*
X-142240Y-83270D01*
G02X-145331Y-84550I-3091J3091D01*
G01X-146870D01*
G03X-148850Y-86530I0J-1980D01*
G01Y-91194D01*
Y-91197D01*
Y-108250D01*
G03X-146919Y-112913I6594J0D01*
G01X-144881Y-114950D01*
X-142003Y-117828D01*
G02X-139850Y-123026I-5198J-5198D01*
G01Y-125561D01*
X-139671Y-125740D01*
Y-127532D01*
X-139850Y-127711D01*
Y-129581D01*
G03X-139461Y-129970I389J0D01*
G02X-138940Y-130491I0J-521D01*
G01Y-131919D01*
G02X-139541Y-132520I-601J0D01*
G03X-139850Y-132829I0J-309D01*
G01Y-152700D01*
G02X-142000Y-154850I-2150J0D01*
G01X-142525D01*
G03X-143421Y-155221I0J-1267D01*
G01X-143901Y-155701D01*
G03X-144409Y-156929I1229J-1229D01*
G01X-142126Y-63147D02*
X-141176Y-64920D01*
G03X-140581Y-65100I388J208D01*
G01X-140426Y-65017D01*
G03X-140323Y-64941I-208J388D01*
G01X-140095Y-64713D01*
G03X-138971Y-62000I-2713J2713D01*
G01Y-61100D01*
G03X-139212Y-60518I-823J0D01*
G01X-139501Y-60230D01*
G03X-140779Y-59700I-1279J-1279D01*
G01X-144459D01*
G03X-146650Y-61891I0J-2191D01*
G01Y-62331D01*
G02X-147300Y-63900I-2219J0D01*
G03X-154900Y-82248I18348J-18348D01*
G01Y-95546D01*
X-153990Y-96456D01*
Y-97696D01*
X-154900Y-98606D01*
Y-103161D01*
G03X-154581Y-103480I319J0D01*
G02X-154061Y-104000I0J-520D01*
G01Y-105760D01*
G02X-154561Y-106260I-500J0D01*
G03X-154900Y-106599I0J-339D01*
G01Y-109460D01*
G03X-154460Y-109900I440J0D01*
G01X-154451D01*
G02X-153991Y-110360I0J-460D01*
G01Y-112560D01*
G02X-154491Y-113060I-500J0D01*
G03X-154900Y-113469I0J-409D01*
G01Y-116971D01*
G03X-154551Y-117320I349J0D01*
G02X-153991Y-117880I0J-560D01*
G01Y-119520D01*
G02X-154571Y-120100I-580J0D01*
G01X-154621D01*
G03X-154900Y-120379I0J-279D01*
G01Y-129095D01*
G03X-152145Y-135745I9405J0D01*
G03X-148996Y-137050I3150J3150D01*
G01X-147400D01*
G03X-145996Y-136468I0J1986D01*
G01X-144409Y-134882D01*
G01X-139173Y-68659D02*
X-140123Y-66886D01*
G02X-139943Y-66290I388J208D01*
G01X-139788Y-66207D01*
G03X-139368Y-65895I-845J1578D01*
G01X-139141Y-65668D01*
G03X-137621Y-62000I-3668J3668D01*
G01Y-61100D01*
G03X-138258Y-59564I-2173J0D01*
G01X-138546Y-59275D01*
G03X-140779Y-58350I-2233J-2233D01*
G01X-144459D01*
G03X-148000Y-61891I0J-3541D01*
G01Y-62331D01*
G02X-148255Y-62945I-869J0D01*
G03X-156250Y-82248I19303J-19303D01*
G01Y-129095D01*
G03X-153100Y-136700I10755J0D01*
G03X-148996Y-138400I4104J4104D01*
G01X-147400D01*
G02X-145698Y-139105I0J-2407D01*
G01X-144409Y-140394D01*
G01X-128661Y-151417D02*
G03X-126579Y-153500I2083J0D01*
G01X-126500D01*
G03X-125500Y-152500I0J1000D01*
G01Y-122444D01*
G03X-131400Y-108200I-20144J0D01*
G02X-134800Y-99992I8208J8208D01*
G01Y-99300D01*
G02X-133569Y-96328I4203J0D01*
G01X-133073Y-95832D01*
G02X-132653Y-95520I1266J-1266D01*
G01X-132498Y-95437D01*
G03X-132318Y-94841I-208J388D01*
G01X-133268Y-93068D01*
G01X-128661Y-156929D02*
G02X-126582Y-154850I2079J0D01*
G01X-126500D01*
G03X-124150Y-152500I0J2350D01*
G01Y-132379D01*
G02X-123811Y-132040I339J0D01*
G03X-123241Y-131470I0J570D01*
G01Y-129930D01*
G03X-123771Y-129400I-530J0D01*
G02X-124150Y-129021I0J379D01*
G01Y-127392D01*
X-124021Y-127263D01*
Y-125559D01*
X-124150Y-125430D01*
Y-122444D01*
G03X-130445Y-107245I-21494J0D01*
G02X-133450Y-99992I7254J7254D01*
G01Y-99300D01*
G02X-132614Y-97283I2853J0D01*
G01X-132118Y-96787D01*
G02X-132015Y-96710I311J-311D01*
G01X-131860Y-96627D01*
G02X-131265Y-96807I208J-388D01*
G01X-130315Y-98580D01*
G01X-136535Y-140000D02*
Y-140165D01*
G03X-134600Y-142100I1935J0D01*
G01X-134050D01*
G03X-133350Y-141400I0J700D01*
G01Y-116266D01*
G03X-133976Y-114755I-2137J0D01*
G01X-139070Y-109660D01*
G02X-140400Y-106450I3210J3210D01*
G01Y-105900D01*
G03X-141348Y-103611I-3237J0D01*
G01X-142205Y-102755D01*
G02X-143800Y-98903I3852J3852D01*
G01Y-98800D01*
G02X-143027Y-96933I2640J0D01*
G01X-141919Y-95826D01*
G02X-141499Y-95514I1266J-1266D01*
G01X-141356Y-95437D01*
G03X-141176Y-94841I-208J388D01*
G01X-142126Y-93068D01*
G01X-136535Y-145512D02*
Y-145385D01*
G02X-134600Y-143450I1935J0D01*
G01X-134050D01*
G03X-132000Y-141400I0J2050D01*
G01Y-126039D01*
G02X-131611Y-125650I389J0D01*
G03X-131090Y-125129I0J521D01*
G01Y-123461D01*
G03X-131691Y-122860I-601J0D01*
G02X-132000Y-122551I0J309D01*
G01Y-120314D01*
X-131831Y-120145D01*
Y-118309D01*
X-132000Y-118140D01*
Y-116266D01*
G03X-133021Y-113800I-3487J0D01*
G01X-138116Y-108706D01*
G02X-139050Y-106450I2256J2256D01*
G01Y-105900D01*
G03X-140394Y-102657I-4587J0D01*
G01X-141250Y-101800D01*
G02X-142450Y-98903I2897J2897D01*
G01Y-98800D01*
G02X-142072Y-97888I1290J0D01*
G01X-140965Y-96780D01*
G02X-140861Y-96703I311J-311D01*
G01X-140719Y-96627D01*
G02X-140123Y-96807I208J-388D01*
G01X-139173Y-98580D01*
G01X-98819Y-63147D02*
X-97869Y-64920D01*
G02X-98049Y-65516I-388J-208D01*
G01X-98437Y-65724D01*
G03X-98606Y-65900I4015J-4015D01*
G03X-98729Y-66038I4184J-3838D01*
G01X-99759Y-67069D01*
G03X-100700Y-69340I2271J-2271D01*
G03X-96730Y-73310I3970J0D01*
G01X-76641D01*
G02X-74871Y-75080I0J-1770D01*
G01Y-154885D01*
G02X-79805Y-166795I-16843J0D01*
G01X-93162Y-180153D01*
G02X-98949Y-182550I-5787J5787D01*
G01X-107150D01*
G02X-108300Y-181400I0J1150D01*
G01Y-172500D01*
G03X-110800Y-170000I-2500J0D01*
G01X-110866D01*
G02X-112913Y-167953I0J2047D01*
G01X-95866Y-68659D02*
X-96816Y-66886D01*
G03X-97412Y-66706I-388J-208D01*
G01X-97611Y-66813D01*
G03X-97736Y-66954I3189J-2926D01*
G01X-98805Y-68023D01*
G03X-99350Y-69340I1317J-1317D01*
G03X-96730Y-71960I2620J0D01*
G01X-76641D01*
G02X-73521Y-75080I0J-3120D01*
G01Y-154885D01*
G02X-78850Y-167750I-18193J0D01*
G01X-80454Y-169354D01*
Y-170583D01*
X-81554Y-171683D01*
X-82783D01*
X-83904Y-172804D01*
G03Y-173427I311J-311D01*
G01X-83887Y-173444D01*
G02Y-174066I-311J-311D01*
G01X-85501Y-175680D01*
G02X-86021I-260J260D01*
G01X-86090Y-175612D01*
G03X-86712I-311J-311D01*
G01X-88924Y-177824D01*
G03Y-178447I311J-311D01*
G01X-88891Y-178480D01*
G02Y-179070I-295J-295D01*
G01X-90581Y-180760D01*
G02X-91051I-235J235D01*
G01X-91144Y-180667D01*
G03X-91767I-311J-311D01*
G01X-92208Y-181108D01*
G02X-98949Y-183900I-6742J6742D01*
G01X-107150D01*
G02X-109650Y-181400I0J2500D01*
G01Y-172500D01*
G03X-110800Y-171350I-1150J0D01*
G03X-112913Y-173463I0J-2113D01*
G01Y-173465D01*
G01Y-151417D02*
Y-152137D01*
G03X-111500Y-153550I1413J0D01*
G01X-110800D01*
G03X-109650Y-152400I0J1150D01*
G01Y-104210D01*
G02X-108243Y-100812I4805J0D01*
G01X-107964Y-100533D01*
G02X-103900Y-98850I4064J-4064D01*
G01X-103521D01*
G03X-100453Y-97579I0J4339D01*
G01X-98800Y-95926D01*
G02X-98380Y-95614I1266J-1266D01*
G01X-98263Y-95551D01*
X-98049Y-95437D01*
G03X-97869Y-94841I-208J388D01*
G01X-98819Y-93068D01*
G01X-112913Y-156929D02*
Y-156313D01*
G02X-111500Y-154900I1413J0D01*
G01X-110800D01*
G03X-108300Y-152400I0J2500D01*
G01Y-131619D01*
G02X-107921Y-131240I379J0D01*
G03X-107390Y-130709I0J531D01*
G01Y-129411D01*
G03X-107881Y-128920I-491J0D01*
G02X-108300Y-128501I0J419D01*
G01Y-125750D01*
X-108051Y-125501D01*
Y-124115D01*
X-108300Y-123866D01*
Y-104210D01*
G02X-107288Y-101767I3455J0D01*
G01X-107009Y-101488D01*
G02X-103900Y-100200I3109J-3109D01*
G01X-103521D01*
G03X-99498Y-98534I0J5689D01*
G01X-97845Y-96881D01*
G02X-97742Y-96804I311J-311D01*
G01X-97412Y-96627D01*
G02X-96816Y-96807I208J-388D01*
G01X-95866Y-98580D01*
G01X-120787Y-140000D02*
Y-140213D01*
G03X-118900Y-142100I1887J0D01*
G03X-117600Y-140800I0J1300D01*
G01Y-113187D01*
G02X-106855Y-87245I36687J0D01*
G01X-103835Y-84226D01*
G02X-101600Y-83300I2235J-2235D01*
G03X-100666Y-82913I0J1321D01*
G01X-98624Y-80871D01*
G02X-98204Y-80559I1266J-1266D01*
G01X-98049Y-80476D01*
G03X-97869Y-79881I-208J388D01*
G01X-98819Y-78108D01*
G01X-120787Y-145512D02*
Y-145337D01*
G02X-118900Y-143450I1887J0D01*
G03X-116250Y-140800I0J2650D01*
G01Y-127339D01*
G02X-115921Y-127010I329J0D01*
G03X-115240Y-126329I0J681D01*
G01Y-125071D01*
G03X-115871Y-124440I-631J0D01*
G02X-116250Y-124061I0J379D01*
G01Y-121197D01*
X-115851Y-120798D01*
Y-118958D01*
X-116250Y-118560D01*
Y-113187D01*
G02X-105900Y-88200I35337J0D01*
G01X-102880Y-85180D01*
G02X-101600Y-84650I1280J-1280D01*
G03X-99711Y-83868I0J2671D01*
G01X-97670Y-81826D01*
G02X-97566Y-81749I311J-311D01*
G01X-97412Y-81666D01*
G02X-96816Y-81847I208J-388D01*
G01X-95866Y-83620D01*
G01X-89961Y-93068D02*
X-89011Y-94841D01*
G02X-89191Y-95437I-388J-208D01*
G01X-89404Y-95551D01*
X-89521Y-95614D01*
G03X-89942Y-95926I845J-1578D01*
G01X-91595Y-97579D01*
G03X-93800Y-102903I5324J-5324D01*
G01Y-169086D01*
G02X-94800Y-171500I-3414J0D01*
G01X-96296Y-172996D01*
G02X-101500Y-175152I-5204J5204D01*
G01X-103200D01*
G02X-105039Y-173312I0J1839D01*
G01Y-173071D01*
G01Y-178583D02*
Y-178341D01*
G02X-103200Y-176502I1839J0D01*
G01X-101500D01*
G03X-95342Y-173951I0J8709D01*
G01X-93845Y-172455D01*
G03X-92450Y-169086I-3369J3369D01*
G01Y-168050D01*
G02X-92100Y-167700I350J0D01*
G03X-91560Y-167160I0J540D01*
G01Y-165940D01*
G03X-92000Y-165500I-440J0D01*
G01X-92010D01*
G02X-92450Y-165060I0J440D01*
G01Y-161850D01*
G02X-92000Y-161400I450J0D01*
G03X-91560Y-160960I0J440D01*
G01Y-159440D01*
G03X-92100Y-158900I-540J0D01*
G02X-92450Y-158550I0J350D01*
G01Y-155088D01*
X-91700Y-154338D01*
Y-153098D01*
X-92450Y-152348D01*
Y-102903D01*
G02X-90640Y-98534I6180J0D01*
G01X-88987Y-96881D01*
G02X-88884Y-96804I311J-311D01*
G01X-88553Y-96627D01*
G02X-87958Y-96807I208J-388D01*
G01X-87008Y-98580D01*
G54D18*
G01X-1174900Y-473500D02*
X-1171300Y-466100D01*
X-1171800Y-465700D01*
X-1175900Y-473200D01*
X-1176200Y-471200D01*
X-1172500Y-465400D01*
X-1175700Y-471300D01*
X-1176500Y-469800D01*
X-1172900Y-464900D01*
X-1173600Y-451800D01*
X-1173700Y-449900D01*
X-1182100D01*
X-1187400Y-473000D01*
X-1182400D01*
X-1177800Y-456000D01*
X-1177000Y-455900D01*
X-1176100Y-468500D01*
X-1173700Y-464500D01*
X-1174600Y-450800D01*
X-1181500Y-450900D01*
X-1186400Y-472100D01*
X-1183100D01*
X-1178300Y-454800D01*
X-1176600Y-455000D01*
X-1175500Y-466300D01*
X-1174600Y-464300D01*
X-1175400Y-451700D01*
X-1181000Y-451800D01*
X-1185300Y-471300D01*
X-1183800Y-471400D01*
X-1179000Y-454300D01*
X-1176200D01*
X-1175200Y-462200D01*
X-1176200Y-452500D01*
X-1180500Y-452800D01*
X-1184300Y-470600D01*
X-1179700Y-453400D01*
X-1176800D01*
G01X-1182820Y-448900D02*
X-1188360Y-473900D01*
X-1181580D01*
X-1177300Y-456700D01*
X-1176920Y-473900D01*
X-1172260D01*
X-1163400Y-456920D01*
X-1167240Y-473900D01*
X-1160380D01*
X-1154840Y-448900D01*
X-1164540D01*
X-1172540Y-464820D01*
X-1172880Y-448900D01*
X-1182820D01*
G01X-1155800Y-449500D02*
X-1161100Y-472900D01*
X-1166100Y-473000D01*
X-1166000Y-471900D01*
X-1161800Y-472100D01*
X-1161300Y-471000D01*
X-1165900Y-471100D01*
X-1165700Y-470000D01*
X-1161300D01*
X-1160800Y-469200D01*
X-1165300Y-469100D01*
X-1165200Y-468100D01*
X-1160700D01*
X-1160400Y-467100D01*
X-1165100Y-467200D01*
X-1164900Y-466300D01*
X-1160300Y-466200D01*
X-1160000Y-465200D01*
X-1164700Y-465300D01*
X-1164400Y-464200D01*
X-1159700Y-464300D01*
X-1159300Y-463100D01*
X-1164700Y-463500D01*
X-1164000Y-462500D01*
X-1159500Y-462600D01*
X-1159000Y-461700D01*
X-1163900D01*
X-1163600Y-460600D01*
X-1159100Y-460800D01*
X-1158800Y-459900D01*
X-1163200D01*
X-1163100Y-459200D01*
X-1158800D01*
X-1158300Y-458500D01*
X-1163000Y-458400D01*
X-1162900Y-457800D01*
X-1158400Y-457900D01*
X-1158200Y-457200D01*
X-1162500Y-457000D01*
X-1163100Y-456500D01*
X-1157800D01*
X-1157500Y-455500D01*
X-1156600Y-449800D01*
X-1164000D01*
X-1164500Y-450700D01*
X-1157600D01*
X-1157800Y-451700D01*
X-1165000Y-451600D01*
X-1165400Y-452400D01*
X-1157900Y-452500D01*
X-1157800Y-453500D01*
X-1165900Y-453200D01*
X-1166200Y-453900D01*
X-1158000Y-454300D01*
X-1158300Y-455300D01*
X-1166600Y-454800D01*
X-1158900Y-455900D01*
X-1167000Y-455600D01*
X-1163500Y-456400D01*
X-1167300Y-456300D01*
X-1171700Y-465200D01*
X-1169200Y-466400D01*
X-1164500Y-457200D01*
X-1166900Y-457100D01*
X-1170600Y-465200D01*
X-1169500Y-465500D01*
X-1166000Y-457800D01*
G01X-1170300Y-466300D02*
X-1174000Y-473600D01*
G01X-1169500Y-466900D02*
X-1172800Y-473000D01*
G01X-1152800Y-456400D02*
X-1156600Y-473100D01*
X-1152200Y-473000D01*
X-1148300Y-456600D01*
X-1149500D01*
X-1152900Y-472000D01*
X-1155600Y-472300D01*
X-1152100Y-456500D01*
X-1150400Y-456400D01*
X-1153600Y-471200D01*
X-1154500Y-471400D01*
X-1151400Y-457200D01*
G01X-1153420Y-455700D02*
X-1157540Y-473900D01*
X-1151380D01*
X-1147440Y-455700D01*
X-1153420D01*
G01X-1151600Y-450100D02*
X-1146700Y-450000D01*
X-1147000Y-451000D01*
X-1151700D01*
G01X-1152020Y-448900D02*
X-1152660Y-451900D01*
X-1146380D01*
X-1145740Y-448900D01*
X-1152020D01*
G01X-1129400Y-468900D02*
X-1131800Y-471900D01*
X-1136500Y-473700D01*
X-1142100Y-473600D01*
X-1144600Y-472300D01*
X-1145800Y-471000D01*
X-1146400Y-469500D01*
X-1146700Y-467600D01*
X-1146500Y-464600D01*
X-1145400Y-461200D01*
X-1143500Y-459100D01*
X-1140200Y-456900D01*
X-1136100Y-456200D01*
X-1132300Y-456400D01*
X-1129400Y-457900D01*
X-1127500Y-460900D01*
X-1132500Y-461000D01*
X-1133400Y-459200D01*
X-1135100Y-458100D01*
X-1136800Y-458000D01*
X-1138600Y-458900D01*
X-1140300Y-460700D01*
X-1141800Y-463600D01*
X-1142400Y-466600D01*
X-1141500Y-470400D01*
X-1140200Y-471500D01*
X-1138300Y-471600D01*
X-1136300Y-471400D01*
X-1134500Y-469100D01*
X-1130300Y-469000D01*
X-1132500Y-471200D01*
X-1134900Y-472000D01*
X-1137200Y-472800D01*
X-1142300Y-472700D01*
X-1144900Y-470600D01*
X-1145800Y-467400D01*
X-1145500Y-465100D01*
X-1144700Y-462000D01*
X-1143300Y-460200D01*
X-1139800Y-457700D01*
X-1135400Y-457000D01*
X-1131300Y-457600D01*
X-1128800Y-460100D01*
X-1132100D01*
X-1134300Y-457900D01*
X-1130100Y-458800D01*
X-1129500Y-459400D01*
X-1132600Y-459000D01*
G01X-1133300Y-461900D02*
Y-461420D01*
X-1133640Y-460240D01*
X-1134300Y-459200D01*
X-1135200Y-458900D01*
X-1136580D01*
X-1138060Y-459820D01*
X-1139360Y-461000D01*
X-1140240Y-462220D01*
X-1140880Y-463920D01*
X-1141300Y-465380D01*
X-1141500Y-467060D01*
Y-468020D01*
X-1141020Y-469220D01*
X-1139780Y-470700D01*
X-1137160D01*
X-1135840Y-469500D01*
X-1134980Y-468200D01*
X-1134940Y-468100D01*
X-1128180D01*
X-1128240Y-468240D01*
X-1128840Y-469340D01*
X-1129020Y-469800D01*
X-1129740Y-470700D01*
X-1130500Y-471460D01*
X-1131660Y-472420D01*
X-1132820Y-473200D01*
X-1133740Y-473740D01*
X-1136380Y-474500D01*
X-1141640D01*
X-1142540Y-474320D01*
X-1144220Y-473760D01*
X-1144900Y-473240D01*
X-1146240Y-471900D01*
X-1146780Y-471180D01*
X-1146940Y-470880D01*
X-1147320Y-469660D01*
X-1147500Y-468640D01*
Y-464780D01*
X-1146940Y-462540D01*
X-1146380Y-461580D01*
X-1145980Y-460780D01*
X-1145420Y-459880D01*
X-1143700Y-458140D01*
X-1142740Y-457380D01*
X-1142000Y-456820D01*
X-1140240Y-456040D01*
X-1139500Y-455660D01*
X-1138800Y-455480D01*
X-1137260Y-455300D01*
X-1134320D01*
X-1132020Y-455500D01*
X-1130940Y-455860D01*
X-1130580Y-456020D01*
X-1129260Y-456780D01*
X-1128940Y-457100D01*
X-1127820Y-458420D01*
X-1127060Y-460300D01*
X-1126900Y-460800D01*
Y-461900D01*
X-1133300D01*
G01X-1137900Y-458000D02*
X-1140300Y-459100D01*
X-1142500Y-460900D01*
X-1143900Y-462600D01*
X-1144800Y-467600D01*
X-1144200Y-470000D01*
X-1141000Y-472300D01*
X-1136400Y-472200D01*
X-1131600Y-469600D01*
X-1135400Y-470400D01*
X-1141100Y-471400D01*
X-1142100Y-470700D01*
X-1142700Y-469000D01*
X-1143100Y-467100D01*
X-1142700Y-464100D01*
X-1140500Y-459900D01*
X-1143400Y-463700D01*
X-1143600Y-465700D01*
X-1143900Y-467700D01*
X-1143000Y-469900D01*
G01X-1113500Y-459200D02*
X-1123500Y-459300D01*
X-1123700Y-460100D01*
X-1114300Y-460000D01*
X-1116500Y-460800D01*
X-1124200Y-461000D01*
X-1124400Y-461900D01*
X-1117600Y-461800D01*
X-1118800Y-462800D01*
X-1124500Y-462700D01*
X-1124600Y-463600D01*
X-1119300Y-463700D01*
X-1120100Y-464800D01*
X-1125000Y-464600D01*
Y-465500D01*
X-1120600Y-465700D01*
X-1120800Y-466700D01*
X-1125300Y-466500D01*
X-1125500Y-467400D01*
X-1121000Y-467600D01*
X-1121200Y-468700D01*
X-1125600Y-468400D01*
X-1125900Y-469100D01*
X-1121500Y-469500D01*
X-1121700Y-470700D01*
X-1126100Y-470000D01*
X-1126200Y-470700D01*
X-1121900Y-471200D01*
X-1122100Y-472000D01*
X-1126300Y-471700D01*
X-1126700Y-472300D01*
X-1122100Y-472700D01*
X-1122200Y-473100D01*
X-1126800Y-473200D01*
G01X-1114060Y-460760D02*
X-1114840Y-460920D01*
X-1115740Y-461140D01*
X-1116880Y-461820D01*
X-1117700Y-462640D01*
X-1118620Y-463340D01*
X-1118840Y-464020D01*
X-1119440Y-464820D01*
X-1119660Y-465480D01*
X-1120060Y-466280D01*
X-1120280Y-466960D01*
X-1120480Y-468360D01*
X-1120680Y-468940D01*
X-1120880Y-469940D01*
X-1121080Y-470540D01*
X-1121700Y-472980D01*
X-1121820Y-473900D01*
X-1127640D01*
X-1126920Y-471060D01*
X-1126720Y-470440D01*
X-1126500Y-468800D01*
X-1126320Y-467860D01*
X-1126120Y-467260D01*
X-1125920Y-466260D01*
X-1125720Y-465660D01*
X-1125300Y-464000D01*
X-1125120Y-462220D01*
X-1124920Y-461660D01*
X-1124720Y-460660D01*
X-1124520Y-460060D01*
X-1123720Y-456800D01*
X-1123580Y-455700D01*
X-1117880D01*
X-1118100Y-456160D01*
Y-458740D01*
X-1116500Y-457160D01*
X-1115780Y-456620D01*
X-1114680Y-456060D01*
X-1113560Y-455680D01*
X-1112460Y-455500D01*
X-1111720D01*
X-1112460Y-458440D01*
X-1114060Y-460760D01*
G01X-1123100Y-456500D02*
X-1118900Y-456600D01*
X-1118800Y-457600D01*
X-1123100Y-457500D01*
X-1123300Y-458500D01*
X-1113100Y-458400D01*
X-1112600Y-456400D01*
X-1116100Y-457600D01*
X-1113500D01*
G01X-1105100Y-471100D02*
X-1104060D01*
X-1103780Y-470820D01*
X-1103200Y-470640D01*
X-1102080Y-469740D01*
X-1100800Y-468240D01*
X-1100380Y-467400D01*
X-1100180Y-467100D01*
X-1099960Y-466660D01*
X-1099540Y-465720D01*
X-1099320Y-465060D01*
X-1099100Y-464180D01*
Y-461220D01*
X-1099360Y-460200D01*
X-1099660Y-459900D01*
X-1100700Y-458640D01*
X-1101220Y-458300D01*
X-1103340D01*
X-1103700Y-458640D01*
X-1105300Y-459840D01*
X-1105760Y-460320D01*
X-1106180Y-460940D01*
X-1107060Y-462020D01*
X-1107260Y-462880D01*
X-1107660Y-463660D01*
X-1108100Y-465000D01*
Y-468640D01*
X-1107620Y-469600D01*
X-1107140Y-470340D01*
X-1105980Y-471100D01*
X-1105100D01*
G01X-1112540Y-460460D02*
X-1110680Y-458140D01*
X-1109940Y-457580D01*
X-1109000Y-456840D01*
X-1108480Y-456660D01*
X-1107940Y-456400D01*
X-1107740Y-456200D01*
X-1107480Y-456060D01*
X-1106880Y-455860D01*
X-1106480Y-455660D01*
X-1105960Y-455480D01*
X-1104600Y-455300D01*
X-1103440Y-455100D01*
X-1100940D01*
X-1098240Y-455480D01*
X-1097720Y-455660D01*
X-1097020Y-456020D01*
X-1096180Y-456640D01*
X-1095620Y-456820D01*
X-1095540Y-456900D01*
X-1094200Y-458440D01*
X-1093660Y-459520D01*
X-1093460Y-460100D01*
X-1093100Y-461020D01*
Y-464400D01*
X-1093420Y-465360D01*
X-1094300Y-465520D01*
X-1094720Y-465740D01*
X-1095320Y-465940D01*
X-1096120Y-466340D01*
X-1096720Y-466540D01*
X-1097100Y-466720D01*
X-1098100Y-466920D01*
X-1098520Y-467140D01*
X-1099160Y-467360D01*
X-1101180Y-468700D01*
X-1094660D01*
X-1095220Y-469800D01*
X-1095560Y-470320D01*
X-1097480Y-472220D01*
X-1099940Y-473740D01*
X-1102580Y-474500D01*
X-1108800D01*
X-1109300Y-474340D01*
X-1111220Y-473560D01*
X-1111720Y-473240D01*
X-1113240Y-471720D01*
X-1113560Y-471240D01*
X-1113760Y-470660D01*
X-1114140Y-469980D01*
X-1114320Y-469120D01*
X-1114500Y-468680D01*
Y-464980D01*
X-1114320Y-464260D01*
X-1114140Y-463720D01*
X-1113940Y-463320D01*
X-1113720Y-462660D01*
X-1113560Y-462000D01*
X-1111880Y-460320D01*
X-1112540Y-460460D01*
G01X-1099300Y-466400D02*
X-1093800Y-464400D01*
X-1093900Y-461100D01*
X-1094800Y-459000D01*
X-1096800Y-457300D01*
X-1100000Y-456100D01*
X-1102800Y-455900D01*
X-1106300Y-456300D01*
X-1109600Y-458100D01*
X-1111400Y-460500D01*
X-1112900Y-462600D01*
X-1113600Y-465600D01*
X-1113500Y-469100D01*
X-1112100Y-471900D01*
X-1109600Y-473300D01*
X-1105700Y-473800D01*
X-1101000Y-473400D01*
X-1098200Y-471800D01*
X-1096600Y-470100D01*
X-1096000Y-469500D01*
X-1100800Y-469700D01*
X-1102300Y-471100D01*
X-1097900Y-470400D01*
X-1100300Y-471800D01*
X-1103200Y-471400D01*
X-1100600Y-472600D01*
X-1103000D01*
X-1103700Y-471900D01*
X-1103400Y-473000D01*
X-1104600Y-471900D01*
X-1106200D01*
X-1104100Y-473100D01*
X-1107200Y-472700D01*
X-1110100Y-472100D01*
X-1111500Y-470900D01*
X-1112600Y-468600D01*
X-1112700Y-466000D01*
X-1112400Y-463700D01*
X-1111400Y-461600D01*
X-1109600Y-459500D01*
X-1108100Y-458200D01*
X-1105900Y-457200D01*
X-1102200Y-456700D01*
X-1099600Y-457300D01*
X-1097000Y-458400D01*
X-1095500Y-459500D01*
X-1094600Y-461900D01*
X-1094500Y-463900D01*
X-1098800Y-465200D01*
X-1098600Y-464000D01*
X-1095100Y-463100D01*
X-1095300Y-462000D01*
X-1098500Y-463000D01*
X-1098600Y-461700D01*
X-1095600Y-461300D01*
X-1095900Y-460200D01*
X-1098400Y-460700D01*
X-1098900Y-459900D01*
X-1096600Y-459400D01*
X-1097100Y-458900D01*
X-1099400Y-459000D01*
X-1098800Y-458500D01*
X-1100600Y-458000D01*
X-1102400Y-457400D01*
X-1104200Y-457500D01*
X-1106200Y-458100D01*
X-1107900Y-459000D01*
X-1110500Y-462200D01*
X-1111800Y-464800D01*
Y-467700D01*
X-1110700Y-470300D01*
X-1108700Y-472000D01*
X-1106600Y-471900D01*
X-1107900Y-470300D01*
X-1108900Y-468700D01*
Y-465500D01*
X-1107900Y-462300D01*
X-1106500Y-459900D01*
X-1104100Y-458200D01*
X-1108000Y-460000D01*
X-1108100Y-461500D01*
X-1108700Y-461200D01*
X-1110300Y-463600D01*
X-1111000Y-466000D01*
X-1110700Y-468100D01*
X-1109500Y-470600D01*
X-1107700Y-471400D01*
X-1109300Y-469100D01*
X-1109800Y-467600D01*
X-1108600Y-462200D01*
X-1110400Y-466800D01*
G01X-1113600Y-460900D02*
X-1112100Y-459000D01*
G01X-1093100Y-469400D02*
X-1087900Y-469700D01*
X-1086500Y-471400D01*
X-1083400Y-472300D01*
X-1081000Y-472000D01*
X-1079300Y-470600D01*
X-1079000Y-468900D01*
X-1079500Y-467700D01*
X-1080300Y-466600D01*
X-1081800Y-466000D01*
X-1083300Y-465500D01*
X-1085300Y-465000D01*
X-1087900Y-464000D01*
X-1089100Y-463200D01*
X-1089800Y-461000D01*
X-1089500Y-459000D01*
X-1088600Y-457700D01*
X-1086500Y-456700D01*
X-1084600Y-456100D01*
X-1081900Y-455900D01*
X-1079900Y-455800D01*
X-1076900Y-456300D01*
X-1075000Y-457000D01*
X-1073700Y-458000D01*
X-1073300Y-459400D01*
X-1077600Y-459500D01*
X-1078100Y-458800D01*
X-1074300Y-458500D01*
X-1074600Y-457800D01*
X-1078200Y-458200D01*
X-1076000Y-457400D01*
X-1079100Y-457700D01*
X-1077100Y-456900D01*
X-1080100Y-457300D01*
X-1079200Y-456600D01*
X-1083100Y-456800D01*
X-1080600Y-457300D01*
X-1083400Y-457700D01*
X-1083600Y-457000D01*
X-1087900Y-458400D01*
X-1084000Y-458100D01*
X-1088600Y-459100D01*
X-1088800Y-461500D01*
X-1087700Y-463600D01*
X-1084400Y-464300D01*
X-1081200Y-465400D01*
X-1078800Y-467300D01*
X-1078300Y-470500D01*
X-1079900Y-472600D01*
X-1083500Y-473300D01*
X-1085600Y-472600D01*
X-1088800Y-470500D01*
X-1092600Y-470200D01*
X-1092100Y-471800D01*
X-1091700Y-471300D01*
X-1089300Y-471500D01*
X-1091300Y-472300D01*
X-1088700Y-471600D01*
X-1084000Y-473500D01*
X-1089100D01*
X-1091000Y-472900D01*
X-1087200Y-472800D01*
X-1082700Y-473700D01*
X-1079000Y-473600D01*
X-1076500Y-472300D01*
X-1074700Y-470600D01*
X-1074300Y-467300D01*
X-1074800Y-465300D01*
X-1078800Y-463600D01*
X-1081600Y-462900D01*
X-1083400Y-462500D01*
X-1084800Y-461500D01*
X-1085000Y-458900D01*
X-1088100Y-459800D01*
X-1087200Y-462700D01*
X-1085000Y-463400D01*
X-1082000Y-464100D01*
X-1079600Y-465100D01*
X-1078200Y-466500D01*
X-1077700Y-468500D01*
X-1077500Y-470100D01*
X-1079200Y-472800D01*
X-1076800Y-471400D01*
X-1075300Y-470000D01*
X-1077300Y-470900D01*
X-1075000Y-468800D01*
X-1075200Y-466100D01*
X-1082700Y-462700D01*
X-1084200Y-462900D01*
X-1086600Y-461800D01*
X-1087200Y-460300D01*
X-1085800Y-459800D01*
X-1086600Y-461000D01*
X-1085300Y-460400D01*
X-1085600Y-461400D01*
X-1076700Y-466500D01*
X-1075900Y-467100D01*
X-1075700Y-468400D01*
X-1076800Y-469500D01*
X-1077800Y-466200D01*
X-1075900Y-468800D01*
G01X-1093780Y-468700D02*
X-1087100D01*
Y-469740D01*
X-1086800Y-470060D01*
X-1086520Y-470600D01*
X-1085820Y-470820D01*
X-1085660Y-471000D01*
X-1085120Y-471260D01*
X-1084400Y-471500D01*
X-1082360D01*
X-1080540Y-470600D01*
X-1080100Y-470140D01*
Y-469780D01*
X-1079840Y-469380D01*
X-1080380Y-467740D01*
X-1081440Y-466940D01*
X-1082560Y-466720D01*
X-1085740Y-465920D01*
X-1086940Y-465520D01*
X-1087600Y-465360D01*
X-1087740Y-465200D01*
X-1088540Y-464800D01*
X-1089140Y-464200D01*
X-1089540Y-464000D01*
X-1089800Y-463740D01*
X-1090000Y-463340D01*
X-1090180Y-463180D01*
X-1090500Y-462200D01*
Y-459800D01*
X-1090320Y-459260D01*
X-1090140Y-458500D01*
X-1090000Y-458260D01*
X-1089000Y-457260D01*
X-1088860Y-456940D01*
X-1085920Y-455480D01*
X-1083620Y-455100D01*
X-1082060Y-454900D01*
X-1080520D01*
X-1078580Y-455100D01*
X-1076240Y-455480D01*
X-1075120Y-455860D01*
X-1074800Y-456020D01*
X-1073680Y-456760D01*
X-1073160Y-457300D01*
X-1072620Y-458020D01*
X-1072500Y-458240D01*
Y-460300D01*
X-1078500D01*
Y-459200D01*
X-1079580Y-458380D01*
X-1080160Y-458100D01*
X-1082380D01*
X-1083280Y-458360D01*
X-1084020Y-458940D01*
X-1084340Y-459900D01*
X-1084060Y-460720D01*
X-1083740Y-461340D01*
X-1081860Y-462280D01*
X-1079400Y-462500D01*
X-1078660Y-462680D01*
X-1078100Y-462860D01*
X-1076500Y-463460D01*
X-1075320Y-463860D01*
X-1075060Y-464000D01*
X-1073820Y-465220D01*
X-1073480Y-466260D01*
X-1073300Y-467160D01*
Y-468420D01*
X-1073860Y-470700D01*
X-1074000Y-470960D01*
X-1075140Y-472300D01*
X-1075280Y-472440D01*
X-1076600Y-473380D01*
X-1077320Y-473740D01*
X-1079600Y-474500D01*
X-1088240D01*
X-1089160Y-474320D01*
X-1089920Y-474120D01*
X-1090860Y-473760D01*
X-1091560Y-473400D01*
X-1092700Y-472460D01*
X-1093180Y-471980D01*
X-1093340Y-471480D01*
X-1093520Y-471100D01*
X-1093700Y-470320D01*
X-1093780Y-468700D01*
G01X-1095100D02*
X-1092800D01*
G01X-1058300Y-469400D02*
X-1055400Y-467100D01*
X-1053900Y-463700D01*
X-1054400Y-461200D01*
X-1055900Y-459900D01*
X-1054800Y-463500D01*
X-1055400Y-463600D01*
X-1054600Y-464500D01*
X-1055700D01*
X-1055400Y-465300D01*
X-1056200Y-466800D01*
G01X-1059300Y-457700D02*
X-1059100Y-455600D01*
X-1055200Y-456300D01*
X-1052700Y-457900D01*
X-1051100Y-460800D01*
X-1050900Y-465200D01*
X-1052900Y-469400D01*
X-1055300Y-471900D01*
X-1059000Y-473500D01*
X-1066000D01*
X-1068000Y-471900D01*
X-1070200Y-468700D01*
X-1070600Y-464500D01*
X-1069000Y-460500D01*
X-1066000Y-457500D01*
X-1063000Y-456500D01*
X-1059200Y-456000D01*
X-1053000Y-458500D01*
X-1052000Y-461500D01*
Y-465700D01*
X-1053400Y-468600D01*
X-1055700Y-471000D01*
X-1058900Y-472600D01*
X-1063700Y-473000D01*
X-1065900Y-473600D01*
X-1068300Y-472900D01*
X-1070600Y-469300D01*
X-1065100Y-472600D01*
X-1060800Y-472200D01*
X-1057200Y-470700D01*
X-1055200Y-469100D01*
X-1053300Y-466500D01*
X-1052500Y-463400D01*
X-1052900Y-460100D01*
X-1057000Y-457400D01*
X-1058700Y-457200D01*
X-1057000Y-458500D01*
X-1055100Y-459800D01*
X-1053800Y-460900D01*
X-1053400Y-463100D01*
X-1053600Y-465600D01*
X-1054800Y-467500D01*
X-1056400Y-469200D01*
X-1058500Y-470200D01*
X-1060200Y-470700D01*
X-1061500Y-471400D01*
X-1063300Y-471600D01*
X-1065400Y-471500D01*
X-1069000Y-469300D01*
X-1069600Y-466400D01*
X-1069700Y-463700D01*
X-1068600Y-461200D01*
X-1066700Y-459200D01*
X-1063900Y-457600D01*
X-1061100Y-457000D01*
X-1059600D01*
X-1060200Y-457500D01*
X-1063300Y-458000D01*
X-1065300Y-459500D01*
X-1066900Y-460600D01*
X-1067900Y-462100D01*
X-1068800Y-464300D01*
X-1068700Y-466900D01*
X-1068200Y-469100D01*
X-1066900Y-470200D01*
X-1064300Y-470900D01*
X-1065700Y-469300D01*
X-1065800Y-465900D01*
X-1065300Y-462900D01*
X-1061200Y-458200D01*
X-1063600Y-458900D01*
X-1066400Y-461300D01*
X-1067800Y-464200D01*
Y-467200D01*
X-1067400Y-469300D01*
X-1066300Y-469700D01*
X-1067100Y-466400D01*
X-1066600Y-463400D01*
X-1064700Y-460000D01*
X-1062600Y-458800D01*
X-1065300Y-461700D01*
X-1066700Y-467400D01*
G01X-1060840Y-455100D02*
X-1057160D01*
X-1055260Y-455480D01*
X-1054740Y-455640D01*
X-1053380Y-456420D01*
X-1052660Y-456800D01*
X-1052020Y-457420D01*
X-1051820Y-458020D01*
X-1051200Y-458660D01*
X-1051000Y-459060D01*
X-1050840Y-459200D01*
X-1050700Y-459780D01*
Y-460140D01*
X-1050400Y-460460D01*
X-1050280Y-460680D01*
X-1050100Y-461740D01*
Y-464240D01*
X-1050280Y-465160D01*
X-1050480Y-465980D01*
X-1050680Y-467120D01*
X-1051220Y-468180D01*
X-1051840Y-469020D01*
X-1052040Y-469600D01*
X-1052740Y-470500D01*
X-1054480Y-472240D01*
X-1055000Y-472580D01*
X-1055420Y-472780D01*
X-1056220Y-473380D01*
X-1056920Y-473740D01*
X-1059380Y-474500D01*
X-1065600D01*
X-1067860Y-473740D01*
X-1068160Y-473600D01*
X-1069500Y-472460D01*
X-1069820Y-472120D01*
X-1070380Y-471200D01*
X-1071140Y-469860D01*
X-1071300Y-469400D01*
Y-464580D01*
X-1071120Y-463880D01*
X-1070740Y-462900D01*
X-1070540Y-462320D01*
X-1069980Y-461000D01*
X-1068840Y-459500D01*
X-1066900Y-457560D01*
X-1066180Y-457020D01*
X-1065400Y-456620D01*
X-1064440Y-456040D01*
X-1063500Y-455660D01*
X-1062940Y-455480D01*
X-1060840Y-455100D01*
G01X-1057800Y-458580D02*
X-1057000Y-459120D01*
X-1056760Y-459840D01*
X-1056340Y-460460D01*
X-1056100Y-461640D01*
Y-463760D01*
X-1056320Y-464860D01*
X-1056720Y-466060D01*
X-1056940Y-466920D01*
X-1057200Y-467460D01*
X-1057640Y-467880D01*
X-1058040Y-468480D01*
X-1059960Y-470420D01*
X-1061020Y-470840D01*
X-1061420Y-471100D01*
X-1062720D01*
X-1063340Y-470840D01*
X-1063860Y-470600D01*
X-1064360Y-470080D01*
X-1064820Y-469400D01*
X-1065100Y-468840D01*
Y-464920D01*
X-1064880Y-464120D01*
X-1064420Y-462780D01*
X-1064160Y-462520D01*
X-1063620Y-461700D01*
X-1063200Y-460840D01*
X-1062500Y-460140D01*
X-1062120Y-459860D01*
X-1061720Y-459360D01*
X-1060600Y-458580D01*
X-1060040Y-458300D01*
X-1058360D01*
X-1057800Y-458580D01*
G01X-1040300Y-459100D02*
X-1041400Y-464800D01*
G01X-1044800Y-458200D02*
X-1041400D01*
X-1044300Y-472700D01*
X-1047400Y-472300D01*
X-1044100Y-458800D01*
X-1042400Y-459100D01*
X-1045100Y-471900D01*
X-1046500D01*
X-1043400Y-459700D01*
X-1045600Y-471500D01*
G01X-1036600Y-449900D02*
X-1036800Y-451300D01*
X-1038600Y-452400D01*
X-1039800Y-456100D01*
X-1033700Y-456500D01*
X-1032300Y-452100D01*
X-1028400Y-452000D01*
X-1028900Y-455400D01*
X-1027200Y-456600D01*
X-1025900Y-456800D01*
X-1026200Y-458200D01*
X-1030000Y-458400D01*
X-1031800Y-468900D01*
X-1030400Y-471700D01*
X-1029400D01*
X-1029600Y-473300D01*
X-1033100Y-473400D01*
X-1036100Y-472800D01*
X-1036200Y-470500D01*
X-1035900Y-467100D01*
X-1034400Y-461400D01*
X-1033800Y-458800D01*
X-1033500Y-458400D01*
X-1035000Y-458200D01*
X-1039600D01*
X-1040800Y-458300D01*
X-1043600Y-473200D01*
X-1048000Y-473000D01*
X-1045100Y-459400D01*
X-1044900Y-458400D01*
X-1048700D01*
X-1048100Y-456600D01*
X-1044900Y-456400D01*
X-1045200Y-457700D01*
X-1047600Y-457500D01*
X-1026500D01*
G01X-1049580Y-459100D02*
X-1048740Y-455700D01*
X-1044900D01*
Y-454780D01*
X-1044720Y-454060D01*
X-1044340Y-452920D01*
X-1043940Y-452120D01*
X-1043740Y-451520D01*
X-1043600Y-451260D01*
X-1042340Y-450000D01*
X-1042080Y-449860D01*
X-1040580Y-449480D01*
X-1039440Y-449300D01*
X-1036140D01*
X-1035440Y-449400D01*
X-1035480Y-449540D01*
X-1035680Y-450360D01*
X-1035880Y-451280D01*
X-1036000Y-451900D01*
X-1036740D01*
X-1037060Y-452200D01*
X-1037860Y-452600D01*
X-1038220Y-452980D01*
X-1038480Y-453740D01*
X-1038960Y-455700D01*
X-1034020D01*
X-1033720Y-455080D01*
X-1033500Y-453400D01*
X-1032940Y-451100D01*
X-1027260D01*
X-1027280Y-451180D01*
X-1027480Y-452780D01*
X-1027860Y-454280D01*
X-1028100Y-454760D01*
Y-455700D01*
X-1024800D01*
X-1024880Y-455940D01*
X-1025080Y-456940D01*
X-1025280Y-457540D01*
X-1025480Y-458560D01*
X-1025620Y-459100D01*
X-1029100D01*
Y-460000D01*
X-1029280Y-460540D01*
X-1029480Y-461540D01*
X-1029680Y-462140D01*
X-1029880Y-462960D01*
X-1030100Y-464000D01*
X-1030280Y-465560D01*
X-1030480Y-466140D01*
X-1030680Y-467140D01*
X-1030880Y-467740D01*
X-1031040Y-468400D01*
X-1031300Y-468660D01*
Y-469800D01*
X-1030300Y-470560D01*
X-1029940Y-470900D01*
X-1028220D01*
X-1028680Y-472780D01*
X-1028880Y-474120D01*
Y-474140D01*
X-1030720Y-474300D01*
X-1032860D01*
X-1034380Y-474120D01*
X-1035860Y-473740D01*
X-1036640Y-473280D01*
X-1036960Y-472660D01*
X-1037100Y-472280D01*
Y-470160D01*
X-1036920Y-469260D01*
X-1036700Y-468640D01*
X-1036500Y-466840D01*
X-1036320Y-466260D01*
X-1036120Y-465260D01*
X-1035920Y-464660D01*
X-1035720Y-463660D01*
X-1035520Y-463060D01*
X-1035320Y-462060D01*
X-1035120Y-461440D01*
X-1034820Y-459100D01*
X-1039900D01*
Y-460220D01*
X-1040280Y-461780D01*
X-1040480Y-463380D01*
X-1041280Y-466540D01*
X-1041480Y-467140D01*
X-1041700Y-468200D01*
X-1041880Y-469760D01*
X-1042080Y-470340D01*
X-1042280Y-471360D01*
X-1042480Y-472140D01*
X-1042680Y-472740D01*
X-1042880Y-473740D01*
X-1042940Y-473900D01*
X-1049140D01*
X-1048300Y-470620D01*
X-1048100Y-469020D01*
X-1047920Y-468260D01*
X-1047720Y-467660D01*
X-1047520Y-466660D01*
X-1047320Y-466060D01*
X-1047120Y-465060D01*
X-1046920Y-464460D01*
X-1046700Y-463400D01*
X-1046500Y-462020D01*
X-1046140Y-460500D01*
X-1045900Y-460040D01*
Y-459100D01*
X-1049580D01*
G01X-1038400Y-451100D02*
X-1040600Y-455800D01*
X-1043300D01*
X-1041400Y-451300D01*
X-1038900Y-451000D01*
X-1041200Y-455000D01*
X-1042000Y-455100D01*
X-1040500Y-452000D01*
G01X-1037500Y-449800D02*
X-1037800Y-451000D01*
X-1038500Y-450100D01*
X-1042000Y-450700D01*
X-1043100Y-452300D01*
X-1044100Y-455100D01*
X-1044200Y-456600D01*
X-1036600Y-456800D01*
G01X-1031100Y-472500D02*
X-1031400Y-470900D01*
X-1031900Y-472200D01*
X-1035200D01*
Y-467600D01*
X-1032000Y-453700D01*
X-1030500Y-453800D01*
X-1030000Y-456700D01*
X-1033400Y-471900D01*
X-1034300Y-471600D01*
X-1034200Y-467100D01*
X-1031400Y-454500D01*
X-1030700Y-456500D01*
X-1033700Y-470600D01*
X-1032700Y-461100D01*
G01X-1032000Y-452900D02*
X-1029300D01*
X-1028000Y-457000D01*
X-1029500Y-453600D01*
X-1029100Y-457300D01*
X-1032800Y-472800D01*
X-1030200Y-472600D01*
G54D19*
G01X-1186050Y-540000D02*
Y-552500D01*
X-1180250D01*
G01X-1174975D02*
X-1171350Y-540000D01*
X-1167725Y-552500D01*
G01X-1169030Y-548125D02*
X-1173670D01*
G01X-1159550Y-552500D02*
Y-546875D01*
X-1162450Y-540000D01*
G01X-1156650D02*
X-1159550Y-546875D01*
G01X-1144850Y-552500D02*
X-1150650D01*
Y-540000D01*
X-1144850D01*
G01X-1147170Y-546042D02*
X-1150650D01*
G01X-1138850Y-552500D02*
Y-540000D01*
X-1135225D01*
X-1134065Y-540625D01*
X-1133340Y-541458D01*
X-1133050Y-543125D01*
X-1133340Y-544792D01*
X-1134210Y-545833D01*
X-1135225Y-546458D01*
X-1138850D01*
G01X-1135225D02*
X-1133050Y-552500D01*
G01X-1115105Y-547292D02*
X-1114090Y-545833D01*
X-1113220Y-545000D01*
X-1112060Y-544584D01*
X-1111045Y-545000D01*
X-1110320Y-545833D01*
X-1109740Y-547083D01*
X-1109595Y-548542D01*
X-1109740Y-549792D01*
X-1110320Y-551042D01*
X-1111190Y-552083D01*
X-1112205Y-552500D01*
X-1113365Y-552083D01*
X-1114380Y-550834D01*
X-1114960Y-548958D01*
X-1115105Y-546875D01*
X-1114815Y-544167D01*
X-1114380Y-542708D01*
X-1113655Y-541250D01*
X-1112640Y-540208D01*
X-1111625Y-540000D01*
X-1110610Y-540417D01*
X-1109885Y-541458D01*
M02*
